G04 ================== begin FILE IDENTIFICATION RECORD ==================*
G04 Layout Name:  D:/<user>/Wistron_project/16318-2/gbr/16318-2.brd*
G04 Film Name:    L3*
G04 File Format:  Gerber RS274X*
G04 File Origin:  Cadence Allegro 16.5-S056*
G04 Origin Date:  Mon Aug 07 11:09:40 2017*
G04 *
G04 Layer:  VIA CLASS/L3*
G04 Layer:  PIN/L3*
G04 Layer:  ETCH/L3*
G04 Layer:  DRAWING FORMAT/LAYER_PCB_STORY*
G04 Layer:  DRAWING FORMAT/LAYER_L3*
G04 *
G04 Offset:    (0.00 0.00)*
G04 Mirror:    No*
G04 Mode:      Positive*
G04 Rotation:  0*
G04 FullContactRelief:  No*
G04 UndefLineWidth:     6.00*
G04 ================== end FILE IDENTIFICATION RECORD ====================*
%FSLAX35Y35*MOIN*%
%IR0*IPPOS*OFA0.00000B0.00000*MIA0B0*SFA1.00000B1.00000*%
%ADD11C,.02*%
%ADD14C,.03*%
%ADD13C,.022*%
%ADD16C,.036*%
%ADD12C,.018*%
%ADD10C,.028*%
%ADD15C,.103*%
%ADD17C,.01*%
%ADD18C,.04*%
%ADD19C,.015*%
%ADD20C,.004*%
%ADD21C,.005*%
%ADD22C,.006*%
%ADD23C,.007*%
%ADD24C,.0035*%
%ADD25C,.0055*%
%ADD26C,.00499*%
%ADD29C,.03004*%
%ADD30C,.05204*%
%ADD28C,.04404*%
%ADD27C,.05304*%
G75*
%LPD*%
G75*
G36*
G01X6002Y722992D02*
X23394Y757778D01*
X40764D01*
G02X40940Y757019I0J-400D01*
G03X35305Y752780I8273J-16862D01*
G01X26483D01*
X11125Y722062D01*
X10896D01*
X10750Y721916D01*
Y721708D01*
X10896Y721562D01*
X11000D01*
Y11000D01*
X109197D01*
Y40396D01*
X109343Y40437D01*
G03Y48147I-1075J3855D01*
G01X109197Y48188D01*
Y167744D01*
X109378Y167925D01*
Y431646D01*
G02X124134Y444268I14756J-2315D01*
G01X125760D01*
G03X129864I2052J798D01*
G01X205261D01*
Y439270D01*
X124134D01*
G03X114196Y429331I1J-9939D01*
G01Y6002D01*
X6002D01*
Y722992D01*
G37*
G36*
G01X63121Y752780D02*
G03X57486Y757019I-13908J-12623D01*
G02X57662Y757778I176J359D01*
G01X355907D01*
G02X356080Y757018I0J-400D01*
G03X350373Y752780I8094J-16861D01*
G01X63121D01*
G37*
G36*
G01X133800Y523300D02*
X137650Y527150D01*
X139450D01*
X140300Y526300D01*
Y525000D01*
X138300Y523000D01*
Y511500D01*
X136100Y509300D01*
X120100D01*
X118500Y510900D01*
Y513400D01*
X122400Y517300D01*
Y522700D01*
X123000Y523300D01*
X133800D01*
G37*
G36*
G01X103100Y531000D02*
Y529500D01*
X101900Y528300D01*
X99500D01*
X94800Y533000D01*
Y534600D01*
X95450Y535250D01*
X98850D01*
X103100Y531000D01*
G37*
G36*
G01X166646Y581392D02*
G03X165276Y581635I-898J-1077D01*
G01X165157Y581593D01*
X164192Y582558D01*
Y583514D01*
X164348Y583549D01*
G03X167148Y586233I-835J3673D01*
G03X167155Y586256I-1384J434D01*
G02X167542Y586258I194J-49D01*
G03X168217Y585389I1356J356D01*
G02Y584689I-194J-350D01*
G03X168216Y582239I681J-1225D01*
G02Y581540I-194J-350D01*
G03X168000Y581392I681J-1226D01*
G01X166646D01*
G37*
G36*
G01X169796D02*
G03X169580Y581540I-897J-1078D01*
G02Y582239I194J350D01*
G03X169579Y584689I-682J1225D01*
G02Y585389I194J350D01*
G03X167542Y586970I-681J1225D01*
G02X167155Y586972I-193J51D01*
G03X166996Y587355I-1406J-359D01*
G01Y589023D01*
G03X167045Y590415I-1248J741D01*
G01X166980Y590544D01*
X167841Y591405D01*
X176282D01*
X176942Y590745D01*
Y582583D01*
X175751Y581392D01*
X169796D01*
G37*
G36*
G01X197100Y581600D02*
X196300Y582400D01*
Y587300D01*
X196800Y587800D01*
X200700D01*
X201500Y587000D01*
Y585500D01*
X201900Y585100D01*
X204400D01*
X205300Y584200D01*
Y583633D01*
X205299Y583621D01*
G03Y583309I1393J-156D01*
G01X205300Y583297D01*
Y581900D01*
X205000Y581600D01*
X204104D01*
X204068Y581615D01*
G03X203016I-526J-1300D01*
G01X202980Y581600D01*
X197100D01*
G37*
G36*
G01X266200Y607500D02*
X266102Y607598D01*
Y620502D01*
X269450Y623850D01*
X270900D01*
X274250Y620500D01*
X282400D01*
X282700Y620200D01*
Y614405D01*
G03Y611855I1795J-1275D01*
G01Y610200D01*
X280000Y607500D01*
X266200D01*
G37*
G36*
G01X293522Y6002D02*
Y31185D01*
X298518D01*
Y27329D01*
X298520Y27327D01*
Y11000D01*
X314847D01*
X314849Y10998D01*
X318518D01*
Y6002D01*
X293522D01*
G37*
G36*
G01X356800Y649100D02*
X354400Y651500D01*
Y653900D01*
X354700Y654200D01*
X371700D01*
X372400Y653500D01*
Y649700D01*
X374950Y647150D01*
Y645650D01*
X372900Y643600D01*
X357900D01*
X356800Y644700D01*
Y649100D01*
G37*
G36*
G01X397143Y722062D02*
X381785Y752780D01*
X377973D01*
X377914Y752844D01*
G03X372266Y757018I-13742J-12686D01*
G02X372439Y757778I173J360D01*
G01X384874D01*
X402266Y722992D01*
Y722062D01*
X397143D01*
G37*
G36*
G01X574112Y722993D02*
X591504Y757778D01*
X603939D01*
G02X604112Y757018I0J-400D01*
G03X598464Y752844I8094J-16860D01*
G01X598405Y752780D01*
X594593D01*
X579110Y721812D01*
Y386889D01*
X574112D01*
Y722993D01*
G37*
G36*
G01X661450Y26950D02*
X652952Y18452D01*
X607251D01*
X605852Y19851D01*
Y23552D01*
X606750Y24450D01*
Y75650D01*
X612700Y81600D01*
Y140000D01*
X622100Y149400D01*
X646000D01*
X661450Y133950D01*
Y26950D01*
G37*
G36*
G01X626005Y752780D02*
G03X620298Y757018I-13801J-12623D01*
G02X620471Y757778I173J360D01*
G01X867718D01*
G02X867891Y757018I0J-400D01*
G03X862184Y752780I8094J-16861D01*
G01X626005D01*
G37*
G36*
G01X680900Y17500D02*
X679500Y18900D01*
Y122900D01*
X693600Y137000D01*
X747800D01*
X753900Y130900D01*
Y109600D01*
X732900Y88600D01*
Y19700D01*
X730700Y17500D01*
X680900D01*
G37*
G36*
G01X708100Y326100D02*
X704600Y329600D01*
Y356500D01*
X711900Y363800D01*
X714700D01*
X715400Y363100D01*
Y361300D01*
X718100Y358600D01*
X722300D01*
X723400Y357500D01*
X723600D01*
Y337200D01*
X718807Y332407D01*
G02X718182Y332482I-283J283D01*
G03X714848Y329684I-1883J-1142D01*
G01Y328448D01*
X712500Y326100D01*
X708100D01*
G37*
G36*
G01X914197Y721812D02*
X898714Y752780D01*
X889784D01*
G03X884077Y757018I-13801J-12623D01*
G02X884250Y757778I173J360D01*
G01X901803D01*
X919196Y722993D01*
Y6002D01*
X743201D01*
Y11000D01*
X914197D01*
Y721812D01*
G37*
G36*
G01X747500Y170000D02*
X743500Y174000D01*
Y185610D01*
G03Y185790I-2200J90D01*
G01Y189950D01*
X746700Y193150D01*
X758150D01*
X765700Y200700D01*
X801405D01*
X816667Y215962D01*
Y223233D01*
X813000Y226900D01*
X793300D01*
X791700Y228500D01*
Y239332D01*
X791902Y239533D01*
Y240702D01*
X793424Y242224D01*
X793519Y242215D01*
G03X794367Y242377I154J1494D01*
G01X794410Y242400D01*
X794600D01*
X795300Y243100D01*
Y247350D01*
X795900Y247950D01*
X797700D01*
X798375Y247275D01*
Y242725D01*
X798900Y242200D01*
Y238400D01*
X804400Y232900D01*
X808772D01*
X820955Y245083D01*
Y294810D01*
X829111Y302966D01*
Y313030D01*
X836218Y320137D01*
Y351946D01*
X839384Y355112D01*
X843994D01*
X847654Y351452D01*
Y320207D01*
X846025Y318578D01*
X845925Y318594D01*
G03X843406Y316075I-344J-2175D01*
G01X843422Y315975D01*
X835832Y308385D01*
Y292024D01*
X830448Y286640D01*
Y268625D01*
X828002Y266179D01*
X827964Y266164D01*
G03X826736Y264936I817J-2045D01*
G01X826721Y264898D01*
X826225Y264402D01*
Y255627D01*
G03Y253373I1892J-1127D01*
G01Y251031D01*
X835100Y242156D01*
Y229600D01*
X835050Y229550D01*
Y218881D01*
X819621Y203452D01*
Y190421D01*
X813300Y184100D01*
Y178000D01*
X811350Y176050D01*
X764150D01*
X758100Y170000D01*
X747500D01*
G37*
G36*
G01X800180Y246520D02*
X798200Y248500D01*
X795400D01*
X794400Y247500D01*
X792000D01*
X786500Y253000D01*
Y263200D01*
X786000Y263700D01*
Y272700D01*
X786900Y273600D01*
X787900D01*
X788206Y273906D01*
X788226Y273918D01*
G03X788729Y274429I-788J1279D01*
G01X788900Y274600D01*
Y274852D01*
X788905Y274873D01*
G03Y275521I-1467J324D01*
G01X788900Y275542D01*
Y278103D01*
X788902Y278119D01*
G03Y278589I-1483J235D01*
G01X788900Y278605D01*
Y279500D01*
X789700Y280300D01*
X791300D01*
X791900Y279700D01*
Y274200D01*
X791131Y273431D01*
X791012Y273472D01*
G03X789500Y270950I-493J-1419D01*
G01Y266809D01*
G03X790588Y264222I1038J-1086D01*
G01X790675Y264225D01*
X792187Y262713D01*
X792188Y262622D01*
G03X794887Y261700I1511J12D01*
G01X795611D01*
G03X798033I1211J888D01*
G01X798761D01*
G03X801374Y262050I1211J888D01*
G01X801390Y262090D01*
X805800Y266500D01*
Y301800D01*
X808000Y304000D01*
X814400D01*
X820200Y309800D01*
Y323255D01*
X821212Y324267D01*
X825997D01*
X827956Y326226D01*
Y329228D01*
X827839D01*
X823700Y333367D01*
Y333900D01*
X821800Y335800D01*
Y351400D01*
X825400Y355000D01*
X831900D01*
X834500Y352400D01*
Y320066D01*
X826894Y312460D01*
Y303313D01*
X820090Y296508D01*
X817819D01*
X817240Y295929D01*
Y256332D01*
X808208Y247300D01*
G03X807615Y246717I715J-1321D01*
G01X807602Y246694D01*
X807428Y246520D01*
X800180D01*
G37*
G36*
G01X798800Y267500D02*
X798400Y267900D01*
Y269700D01*
X797600Y270500D01*
X795500D01*
X795200Y270800D01*
Y272389D01*
X795249Y275169D01*
Y275170D01*
G03Y275195I-1512J12D01*
G01X795248Y275196D01*
Y275206D01*
G03X795206Y275553I-1511J-7D01*
G01X795200Y275577D01*
Y276500D01*
X795500Y276800D01*
X800600D01*
X801500Y277700D01*
Y278294D01*
G03Y278396I-1501J51D01*
G01Y279100D01*
X800700Y279900D01*
X795500D01*
X795200Y280200D01*
Y285600D01*
X795700Y286100D01*
X797300D01*
X798600Y287400D01*
Y288500D01*
X797700Y289400D01*
X796400D01*
X795338Y290462D01*
Y291662D01*
X794400Y292600D01*
X790700D01*
X789000Y294300D01*
Y297900D01*
X788050Y298850D01*
Y302050D01*
X788300Y302300D01*
Y322300D01*
X792800Y326800D01*
X806200D01*
X808100Y328700D01*
Y329170D01*
X808247Y329210D01*
G03Y333458I-581J2124D01*
G01X808100Y333498D01*
Y361763D01*
X811545Y365208D01*
X828865D01*
X829529Y364544D01*
Y357936D01*
X828261Y356668D01*
X821532D01*
X819982Y355118D01*
Y351582D01*
X819878Y351478D01*
Y342909D01*
X815096Y338127D01*
Y333398D01*
X816470Y332024D01*
Y329672D01*
X817600Y328542D01*
Y318700D01*
X807000Y308100D01*
X804000D01*
X801200Y305300D01*
Y302600D01*
X804600Y299200D01*
Y268200D01*
X803900Y267500D01*
X798800D01*
G37*
G36*
G01X782847Y294067D02*
X782840Y290947D01*
G03X785631Y290646I1411J-2D01*
G02X786021I195J-42D01*
G03X786086Y290431I1380J300D01*
G01X786100Y290396D01*
Y288547D01*
G03X785996Y287262I1300J-752D01*
G01X786041Y287141D01*
X785400Y286500D01*
X782776D01*
G02X782423Y287089I0J400D01*
G03X780092Y286686I-1323J711D01*
G02X780107Y286107I-268J-297D01*
G01X779400Y285400D01*
Y283900D01*
X778464Y282964D01*
X778233D01*
X778214Y282968D01*
G03X777616I-299J-1472D01*
G01X777597Y282964D01*
X771859D01*
X771847Y282965D01*
G03X771491I-178J-1491D01*
G01X771479Y282964D01*
X768679D01*
X768667Y282965D01*
G03X768311I-178J-1491D01*
G01X768299Y282964D01*
X765559D01*
X765547Y282965D01*
G03X765191I-178J-1491D01*
G01X765179Y282964D01*
X762582D01*
X762557Y282970D01*
G03X761821I-368J-1456D01*
G01X761796Y282964D01*
X759463D01*
X759438Y282970D01*
G03X758702I-368J-1456D01*
G01X758677Y282964D01*
X758464D01*
X758309Y282809D01*
G03X757775Y282275I761J-1295D01*
G01X757200Y281700D01*
X751900D01*
X750508Y283092D01*
Y283475D01*
X750577Y283535D01*
G03X750508Y285861I-984J1135D01*
G01Y289744D01*
G03Y292144I-903J1200D01*
G01Y296074D01*
G03Y298434I-929J1180D01*
G01Y302383D01*
G03Y305049I-692J1333D01*
G01Y306464D01*
X752500Y308456D01*
Y325440D01*
G03Y329428I-934J1994D01*
G01Y330500D01*
X743500Y339500D01*
Y345662D01*
X743502Y345664D01*
Y365500D01*
X746602Y368600D01*
X791200D01*
X801889Y357911D01*
Y348551D01*
X796998Y343660D01*
X790457D01*
G03X787153Y341465I-1123J-1894D01*
G01X787166Y341366D01*
X787008Y341208D01*
Y302800D01*
X785454Y301246D01*
Y295546D01*
X786100Y294900D01*
Y294606D01*
X786087Y294572D01*
G03X786028Y294368I1322J-493D01*
G02X785637Y294367I-196J42D01*
G03X782847Y294067I-1379J-303D01*
G37*
G36*
G01X806096Y370036D02*
X806060Y370000D01*
X803217Y372843D01*
Y375044D01*
X803338Y375165D01*
Y376734D01*
X800987Y379085D01*
Y401172D01*
X804750Y404935D01*
Y408750D01*
X837000Y441000D01*
Y466600D01*
X843900Y473500D01*
X850600D01*
X851696Y472404D01*
Y415638D01*
X851164Y415106D01*
Y415066D01*
X850898Y414800D01*
Y414798D01*
X848670Y412570D01*
Y377409D01*
X841297Y370036D01*
X806096D01*
G37*
G36*
G01X888800Y239400D02*
X891700Y242300D01*
X893500D01*
X894100Y241700D01*
Y228700D01*
X893800Y228400D01*
X891900D01*
X889200Y225700D01*
X887800D01*
X886850Y226650D01*
Y239050D01*
X887200Y239400D01*
X888800D01*
G37*
%LPC*%
G75*
G36*
G01X623921Y114673D02*
G03X623714Y114479I-7J-200D01*
G02X621157Y117217I-2651J88D01*
G03X621364Y117411I7J200D01*
G02X624111Y119973I2651J-88D01*
G03X624318Y120167I7J200D01*
G02X629524Y119369I2651J-88D01*
G01X629503Y119291D01*
X629858Y118627D01*
G03X630560Y118620I353J189D01*
G02X632969Y119973I2313J-1297D01*
G03X633176Y120167I7J200D01*
G02X638382Y119369I2651J-88D01*
G01X638361Y119291D01*
X638717Y118626D01*
G03X639419Y118620I353J189D01*
G02X641638Y114673I2313J-1297D01*
G03X641431Y114479I-7J-200D01*
G02X636225Y115277I-2651J88D01*
G01X636246Y115354D01*
X635889Y116021D01*
G03X635187Y116028I-353J-188D01*
G02X632779Y114673I-2314J1295D01*
G03X632572Y114479I-7J-200D01*
G02X627366Y115277I-2651J88D01*
G01X627387Y115354D01*
X627031Y116021D01*
G03X626329Y116027I-353J-189D01*
G02X623921Y114673I-2314J1296D01*
G37*
G36*
G01Y99712D02*
G03X623714Y99518I-7J-200D01*
G02X621157Y102256I-2651J88D01*
G03X621364Y102450I7J200D01*
G02X624111Y105012I2651J-88D01*
G03X624318Y105206I7J200D01*
G02X629524Y104408I2651J-88D01*
G01X629503Y104330D01*
X629858Y103666D01*
G03X630560Y103659I353J189D01*
G02X632969Y105012I2313J-1297D01*
G03X633176Y105206I7J200D01*
G02X638382Y104408I2651J-88D01*
G01X638361Y104330D01*
X638717Y103665D01*
G03X639419Y103659I353J189D01*
G02X641638Y99712I2313J-1297D01*
G03X641431Y99518I-7J-200D01*
G02X636225Y100316I-2651J88D01*
G01X636246Y100393D01*
X635889Y101060D01*
G03X635187Y101067I-353J-188D01*
G02X632779Y99712I-2314J1295D01*
G03X632572Y99518I-7J-200D01*
G02X627366Y100316I-2651J88D01*
G01X627387Y100393D01*
X627031Y101060D01*
G03X626329Y101066I-353J-189D01*
G02X623921Y99712I-2314J1296D01*
G37*
G36*
G01Y84752D02*
G03X623714Y84558I-7J-200D01*
G02X621157Y87296I-2651J88D01*
G03X621364Y87490I7J200D01*
G02X624111Y90052I2651J-88D01*
G03X624318Y90245I7J200D01*
G02X629524Y89447I2651J-88D01*
G01X629503Y89369D01*
X629858Y88706D01*
G03X630560Y88699I353J188D01*
G02X632969Y90052I2313J-1297D01*
G03X633176Y90245I7J200D01*
G02X638386Y89460I2651J-89D01*
G01X638365Y89383D01*
X638723Y88715D01*
G03X639423Y88707I352J189D01*
G02X641638Y84752I2309J-1305D01*
G03X641431Y84558I-7J-200D01*
G02X636221Y85343I-2651J89D01*
G01X636242Y85420D01*
X635883Y86090D01*
G03X635182Y86098I-353J-189D01*
G02X632779Y84752I-2309J1304D01*
G03X632572Y84558I-7J-200D01*
G02X627366Y85356I-2651J88D01*
G01X627387Y85433D01*
X627030Y86100D01*
G03X626329Y86106I-352J-189D01*
G02X623921Y84752I-2314J1296D01*
G37*
G36*
G01Y69791D02*
G03X623714Y69597I-7J-200D01*
G02X621157Y72335I-2651J88D01*
G03X621364Y72529I7J200D01*
G02X624111Y75091I2651J-88D01*
G03X624318Y75285I7J200D01*
G02X629524Y74487I2651J-88D01*
G01X629503Y74409D01*
X629858Y73745D01*
G03X630560Y73738I353J189D01*
G02X632969Y75091I2313J-1297D01*
G03X633176Y75285I7J200D01*
G02X638382Y74487I2651J-88D01*
G01X638361Y74409D01*
X638717Y73744D01*
G03X639419Y73738I353J189D01*
G02X641638Y69791I2313J-1297D01*
G03X641431Y69597I-7J-200D01*
G02X636225Y70395I-2651J88D01*
G01X636246Y70472D01*
X635889Y71139D01*
G03X635187Y71146I-353J-188D01*
G02X632779Y69791I-2314J1295D01*
G03X632572Y69597I-7J-200D01*
G02X627366Y70395I-2651J88D01*
G01X627387Y70472D01*
X627031Y71139D01*
G03X626329Y71145I-353J-189D01*
G02X623921Y69791I-2314J1296D01*
G37*
G36*
G01X702661Y114673D02*
G03X702454Y114479I-7J-200D01*
G02X699897Y117217I-2651J88D01*
G03X700104Y117411I7J200D01*
G02X702851Y119973I2651J-88D01*
G03X703058Y120167I7J200D01*
G02X708264Y119369I2651J-88D01*
G01X708243Y119291D01*
X708598Y118627D01*
G03X709300Y118620I353J189D01*
G02X711709Y119973I2313J-1297D01*
G03X711916Y120167I7J200D01*
G02X717122Y119369I2651J-88D01*
G01X717101Y119291D01*
X717457Y118626D01*
G03X718159Y118620I353J189D01*
G02X720378Y114673I2313J-1297D01*
G03X720171Y114479I-7J-200D01*
G02X714965Y115277I-2651J88D01*
G01X714986Y115354D01*
X714629Y116021D01*
G03X713927Y116028I-353J-188D01*
G02X711519Y114673I-2314J1295D01*
G03X711312Y114479I-7J-200D01*
G02X706106Y115277I-2651J88D01*
G01X706127Y115354D01*
X705771Y116021D01*
G03X705069Y116027I-353J-189D01*
G02X702661Y114673I-2314J1296D01*
G37*
G36*
G01Y99712D02*
G03X702454Y99518I-7J-200D01*
G02X699897Y102256I-2651J88D01*
G03X700104Y102450I7J200D01*
G02X702851Y105012I2651J-88D01*
G03X703058Y105206I7J200D01*
G02X708298Y104541I2651J-88D01*
G01X708281Y104469D01*
X708657Y103767D01*
G03X709351Y103747I353J189D01*
G02X711709Y105012I2261J-1385D01*
G03X711916Y105206I7J200D01*
G02X717156Y104543I2651J-89D01*
G01X717140Y104470D01*
X717516Y103767D01*
G03X718210Y103747I353J189D01*
G02X720378Y99712I2262J-1385D01*
G03X720171Y99518I-7J-200D01*
G02X714931Y100181I-2651J89D01*
G01X714947Y100254D01*
X714569Y100959D01*
G03X713876Y100979I-352J-189D01*
G02X711519Y99712I-2263J1383D01*
G03X711312Y99518I-7J-200D01*
G02X706072Y100182I-2651J89D01*
G01X706088Y100255D01*
X705711Y100959D01*
G03X705018Y100979I-352J-189D01*
G02X702661Y99712I-2263J1383D01*
G37*
G36*
G01Y84752D02*
G03X702454Y84558I-7J-200D01*
G02X699897Y87296I-2651J88D01*
G03X700104Y87490I7J200D01*
G02X702851Y90052I2651J-88D01*
G03X703058Y90245I7J200D01*
G02X708264Y89447I2651J-88D01*
G01X708243Y89369D01*
X708598Y88706D01*
G03X709300Y88699I353J188D01*
G02X711709Y90052I2313J-1297D01*
G03X711916Y90245I7J200D01*
G02X717126Y89460I2651J-89D01*
G01X717105Y89383D01*
X717463Y88715D01*
G03X718163Y88707I352J189D01*
G02X720378Y84752I2309J-1305D01*
G03X720171Y84558I-7J-200D01*
G02X714961Y85343I-2651J89D01*
G01X714982Y85420D01*
X714623Y86090D01*
G03X713922Y86098I-353J-189D01*
G02X711519Y84752I-2309J1304D01*
G03X711312Y84558I-7J-200D01*
G02X706106Y85356I-2651J88D01*
G01X706127Y85433D01*
X705770Y86100D01*
G03X705069Y86106I-352J-189D01*
G02X702661Y84752I-2314J1296D01*
G37*
G36*
G01Y69791D02*
G03X702454Y69597I-7J-200D01*
G02X699897Y72335I-2651J88D01*
G03X700104Y72529I7J200D01*
G02X702851Y75091I2651J-88D01*
G03X703058Y75285I7J200D01*
G02X708264Y74487I2651J-88D01*
G01X708243Y74409D01*
X708598Y73745D01*
G03X709300Y73738I353J189D01*
G02X711709Y75091I2313J-1297D01*
G03X711916Y75285I7J200D01*
G02X717122Y74487I2651J-88D01*
G01X717101Y74409D01*
X717457Y73744D01*
G03X718159Y73738I353J189D01*
G02X720378Y69791I2313J-1297D01*
G03X720171Y69597I-7J-200D01*
G02X714965Y70395I-2651J88D01*
G01X714986Y70472D01*
X714629Y71139D01*
G03X713927Y71146I-353J-188D01*
G02X711519Y69791I-2314J1295D01*
G03X711312Y69597I-7J-200D01*
G02X706106Y70395I-2651J88D01*
G01X706127Y70472D01*
X705771Y71139D01*
G03X705069Y71145I-353J-189D01*
G02X702661Y69791I-2314J1296D01*
G37*
G36*
G01X755010Y183897D02*
G03X755071Y183298I292J-273D01*
G02X752190Y183003I-1272J-1798D01*
G03X752129Y183602I-292J273D01*
G02X755010Y183897I1272J1798D01*
G37*
G36*
G01X817518Y299198D02*
G02X817316Y299400I0J202D01*
G01Y300200D01*
G02X817518Y300402I202J0D01*
G01X820718D01*
G02X820920Y300200I0J-202D01*
G01Y299400D01*
G02X820718Y299198I-202J0D01*
G01X817518D01*
G37*
G36*
G01Y301398D02*
G02X817316Y301600I0J202D01*
G01Y302400D01*
G02X817518Y302602I202J0D01*
G01X820718D01*
G02X820920Y302400I0J-202D01*
G01Y301600D01*
G02X820718Y301398I-202J0D01*
G01X817518D01*
G37*
G36*
G01X791388Y254397D02*
G02X789691Y254382I-838J-1247D01*
G03X789685Y255042I-229J328D01*
G02X789720Y257558I838J1247D01*
G03X789726Y258231I-213J338D01*
G02X791354Y258217I825J1255D01*
G03X791348Y257544I213J-338D01*
G02X791784Y257104I-826J-1254D01*
G03X792453Y257099I336J217D01*
G02X794925Y257131I1247J-837D01*
G03X795582Y257136I327J231D01*
G02X798060Y257139I1240J-847D01*
G03X798723Y257143I330J226D01*
G02X801220Y257145I1249J-834D01*
G03X801888Y257151I332J223D01*
G02X802294Y257570I1261J-816D01*
G03X802296Y258226I-228J329D01*
G02X804016Y258220I864J1228D01*
G03X804014Y257564I228J-329D01*
G02X801902Y255500I-864J-1228D01*
G03X801234Y255494I-332J-223D01*
G02X798734Y255459I-1262J815D01*
G03X798071Y255455I-330J-226D01*
G02X795597Y255420I-1249J834D01*
G03X794940Y255415I-327J-231D01*
G02X792439Y255447I-1240J847D01*
G03X791770Y255452I-336J-217D01*
G02X791382Y255057I-1247J837D01*
G03X791388Y254397I229J-328D01*
G37*
G36*
G01X796849Y295732D02*
X793699D01*
G02X792851Y298493I1J1511D01*
G03X792852Y299154I-225J331D01*
G02X792444Y299571I849J1239D01*
G03X791776Y299574I-335J-219D01*
G02X791783Y301228I-1250J832D01*
G03X792451Y301225I335J219D01*
G02X794841Y299415I1251J-831D01*
G03X795144Y298754I303J-261D01*
G01X796849D01*
G02X798360Y297253I0J-1511D01*
G01Y297158D01*
X798351Y297074D01*
G02X796849Y295732I-1502J170D01*
G37*
G36*
G01X780535Y348341D02*
X780342Y348535D01*
X780259D01*
G02X778070Y350938I4J2202D01*
G03X777635Y351373I-398J37D01*
G02X779627Y353365I-201J2193D01*
G03X780062Y352930I398J-37D01*
G02X782465Y350742I201J-2193D01*
G01Y350659D01*
X782659Y350465D01*
X782742D01*
G02X784930Y348062I-5J-2202D01*
G03X785365Y347627I398J-37D01*
G02X783373Y345635I201J-2193D01*
G03X782938Y346070I-398J37D01*
G02X780535Y348259I-201J2193D01*
G01Y348341D01*
G37*
G36*
G01X763353Y348041D02*
X763160Y348235D01*
X763077D01*
G02X760888Y350638I4J2202D01*
G03X760453Y351073I-398J37D01*
G02X762445Y353065I-201J2193D01*
G03X762880Y352630I398J-37D01*
G02X765283Y350442I201J-2193D01*
G01Y350359D01*
X765477Y350165D01*
X765560D01*
G02X767748Y347762I-5J-2202D01*
G03X768183Y347327I398J-37D01*
G02X766191Y345335I201J-2193D01*
G03X765756Y345770I-398J37D01*
G02X763353Y347959I-201J2193D01*
G01Y348041D01*
G37*
G36*
G01X752635Y341341D02*
X752442Y341535D01*
X752359D01*
G02X750170Y343938I4J2202D01*
G03X749735Y344373I-398J37D01*
G02X751727Y346365I-201J2193D01*
G03X752162Y345930I398J-37D01*
G02X754565Y343742I201J-2193D01*
G01Y343659D01*
X754759Y343465D01*
X754842D01*
G02X757030Y341062I-5J-2202D01*
G03X757465Y340627I398J-37D01*
G02X755473Y338635I201J-2193D01*
G03X755038Y339070I-398J37D01*
G02X752635Y341259I-201J2193D01*
G01Y341341D01*
G37*
G36*
G01X775453Y336041D02*
X775260Y336235D01*
X775177D01*
G02X772988Y338638I4J2202D01*
G03X772553Y339073I-398J37D01*
G02X774545Y341065I-201J2193D01*
G03X774980Y340630I398J-37D01*
G02X777383Y338442I201J-2193D01*
G01Y338359D01*
X777577Y338165D01*
X777660D01*
G02X779848Y335762I-5J-2202D01*
G03X780283Y335327I398J-37D01*
G02X778291Y333335I201J-2193D01*
G03X777856Y333770I-398J37D01*
G02X775453Y335959I-201J2193D01*
G01Y336041D01*
G37*
G36*
G01X764235Y329441D02*
X764042Y329635D01*
X763959D01*
G02X761770Y332038I4J2202D01*
G03X761335Y332473I-398J37D01*
G02X763327Y334465I-201J2193D01*
G03X763762Y334030I398J-37D01*
G02X766165Y331842I201J-2193D01*
G01Y331759D01*
X766359Y331565D01*
X766442D01*
G02X768630Y329162I-5J-2202D01*
G03X769065Y328727I398J-37D01*
G02X767073Y326735I201J-2193D01*
G03X766638Y327170I-398J37D01*
G02X764235Y329359I-201J2193D01*
G01Y329441D01*
G37*
G36*
G01X775578Y289080D02*
G02X774026I-776J-1286D01*
G03X774036Y289759I-206J343D01*
G02X773391Y290959I766J1185D01*
G01X773424Y294103D01*
G02X776063Y294785I1411J-15D01*
G03X776759Y294786I348J197D01*
G02X779400Y294103I1230J-693D01*
G01Y294093D01*
X779401Y294092D01*
G02Y294077I-1412J-8D01*
G01Y294076D01*
X779364Y290954D01*
Y290928D01*
G02X779363Y290900I-1411J36D01*
G01Y290898D01*
X779362Y290849D01*
X779354Y290776D01*
G02X776725Y290247I-1402J168D01*
G03X776029I-348J-197D01*
G02X775568Y289759I-1227J697D01*
G03X775578Y289080I216J-336D01*
G37*
G36*
G01X769910Y294122D02*
X769915Y290861D01*
X769904Y290776D01*
G02X769269Y289758I-1402J167D01*
G03X769279Y289080I217J-336D01*
G02X767727I-776J-1286D01*
G03X767737Y289758I-207J342D01*
G02X767276Y290247I767J1185D01*
G03X766580I-348J-198D01*
G02X764181Y290158I-1227J697D01*
G03X763508Y290145I-332J-223D01*
G02X763067Y289687I-1278J789D01*
G03X763062Y289027I224J-332D01*
G02X760963Y286947I-859J-1233D01*
G03X760305Y286951I-330J-225D01*
G02X758279Y289085I-1232J859D01*
G03X758285Y289760I-211J339D01*
G02X757827Y290246I769J1184D01*
G03X757132I-348J-198D01*
G02X754494Y290944I-1227J698D01*
G01Y294093D01*
G02X757132Y294791I1411J0D01*
G03X757828I348J197D01*
G02X760275Y294804I1227J-697D01*
G03X760965Y294801I346J201D01*
G02X763392Y294781I1208J-712D01*
G03X764090Y294785I348J198D01*
G02X766557Y294792I1235J-683D01*
G03X767257Y294797I349J196D01*
G02X769898Y294300I1241J-673D01*
G01X769910Y294213D01*
Y294122D01*
G37*
G36*
G01X812447Y391984D02*
G03X812421Y391369I242J-318D01*
G02X809611Y391485I-1475J-1635D01*
G03X809637Y392100I-242J318D01*
G02X812447Y391984I1475J1635D01*
G37*
G54D29*
X793701Y231103D03*
Y237402D03*
X799991Y249972D03*
X806968Y253464D03*
X799999Y290944D03*
Y284645D03*
X799974Y272058D03*
X781102Y297244D03*
X771654Y297243D03*
X759058Y300414D03*
X780300Y309300D03*
X777790Y304778D03*
X769768Y304464D03*
X759208Y304284D03*
G54D30*
X841100Y332300D03*
X842600Y339400D03*
G54D28*
X708100Y331410D03*
X712417Y352800D03*
X765900Y191900D03*
X816900Y231700D03*
X823250Y319350D03*
X810300Y326450D03*
X811600Y317300D03*
X817700Y385700D03*
X806400Y398700D03*
X810100Y404934D03*
G54D27*
X618110Y120079D03*
Y105118D03*
Y90157D03*
Y75197D03*
X696850Y120079D03*
Y105118D03*
Y90157D03*
Y75197D03*
%LPD*%
G75*
G54D10*
X8500Y18279D03*
Y28279D03*
Y38279D03*
Y48279D03*
Y58279D03*
Y68279D03*
X13721Y8500D03*
X8500Y13279D03*
Y23279D03*
Y33279D03*
Y43279D03*
Y53279D03*
Y63279D03*
Y78279D03*
Y88279D03*
Y98279D03*
Y108279D03*
Y118279D03*
Y128279D03*
Y73279D03*
Y83279D03*
Y93279D03*
Y103279D03*
Y113279D03*
Y123279D03*
Y133279D03*
Y138279D03*
Y148279D03*
Y158279D03*
Y168279D03*
Y178279D03*
Y188279D03*
Y198279D03*
Y143279D03*
Y153279D03*
Y163279D03*
Y173279D03*
Y183279D03*
Y193279D03*
Y208279D03*
Y218279D03*
Y228279D03*
Y238279D03*
Y248279D03*
Y258279D03*
Y203279D03*
Y213279D03*
Y223279D03*
Y233279D03*
Y243279D03*
Y253279D03*
Y263279D03*
Y268279D03*
Y278279D03*
Y288279D03*
Y298279D03*
Y308279D03*
Y318279D03*
Y328279D03*
Y273279D03*
Y283279D03*
Y293279D03*
Y303279D03*
Y313279D03*
Y323279D03*
Y338279D03*
Y348279D03*
Y358279D03*
Y368279D03*
Y378279D03*
Y388279D03*
Y333279D03*
Y343279D03*
Y353279D03*
Y363279D03*
Y373279D03*
Y383279D03*
Y393279D03*
Y398279D03*
Y408279D03*
Y418279D03*
Y428279D03*
Y438279D03*
Y448279D03*
Y458279D03*
Y403279D03*
Y413279D03*
Y423279D03*
Y433279D03*
Y443279D03*
Y453279D03*
Y468279D03*
Y478279D03*
Y488279D03*
Y498279D03*
Y508279D03*
Y518279D03*
Y528279D03*
Y463279D03*
Y473279D03*
Y483279D03*
Y493279D03*
Y503279D03*
Y513279D03*
Y523279D03*
Y538279D03*
Y548279D03*
Y558279D03*
Y568279D03*
Y578279D03*
Y588279D03*
Y533279D03*
Y543279D03*
Y553279D03*
Y563279D03*
Y573279D03*
Y583279D03*
Y593279D03*
Y598279D03*
Y608279D03*
Y618279D03*
Y628279D03*
Y638279D03*
Y648279D03*
Y658279D03*
Y603279D03*
Y613279D03*
Y623279D03*
Y633279D03*
Y643279D03*
Y653279D03*
Y668279D03*
Y678279D03*
Y688279D03*
Y698279D03*
Y708279D03*
Y718279D03*
Y663279D03*
Y673279D03*
Y683279D03*
Y693279D03*
Y703279D03*
Y713279D03*
X8892Y723187D03*
X11090Y727806D03*
X13500Y732400D03*
X78721Y8500D03*
X68721D03*
X58721D03*
X48721D03*
X38721D03*
X28721D03*
X18721D03*
X73721D03*
X53721D03*
X43721D03*
X33721D03*
X23721D03*
X63721D03*
X28100Y755600D03*
X33100D03*
X69057Y755280D03*
X74057D03*
X20300Y746200D03*
X15800Y736900D03*
X18100Y741500D03*
X22600Y750800D03*
X79057Y755280D03*
X108721Y8500D03*
X98721D03*
X88721D03*
X112197Y65406D03*
Y60406D03*
Y55406D03*
X103721Y8500D03*
X93721D03*
X83721D03*
X112197Y75406D03*
Y85406D03*
Y95406D03*
Y105406D03*
Y115406D03*
Y120406D03*
Y110406D03*
Y100406D03*
Y90406D03*
Y80406D03*
Y70406D03*
Y145406D03*
Y195406D03*
Y185406D03*
Y175406D03*
Y165406D03*
Y155406D03*
Y200406D03*
Y190406D03*
Y180406D03*
Y170406D03*
Y160406D03*
Y150406D03*
Y265406D03*
Y255406D03*
Y245406D03*
Y235406D03*
Y225406D03*
Y215406D03*
Y205406D03*
Y260406D03*
Y250406D03*
Y240406D03*
Y230406D03*
Y220406D03*
Y210406D03*
Y325406D03*
Y315406D03*
Y305406D03*
Y295406D03*
Y285406D03*
Y275406D03*
Y330406D03*
Y320406D03*
Y310406D03*
Y300406D03*
Y290406D03*
Y280406D03*
Y270406D03*
Y390406D03*
Y380406D03*
Y370406D03*
Y360406D03*
Y350406D03*
Y395406D03*
Y385406D03*
Y375406D03*
Y365406D03*
Y355406D03*
Y345406D03*
Y335406D03*
Y340406D03*
Y420406D03*
Y410406D03*
Y400406D03*
Y425406D03*
Y415406D03*
Y405406D03*
X134223Y691027D03*
X144057Y755280D03*
X134057D03*
X124057D03*
X114057D03*
X104057D03*
X94057D03*
X84057D03*
X89057D03*
X99057D03*
X109057D03*
X119057D03*
X129057D03*
X139057D03*
X204057D03*
X194057D03*
X184057D03*
X174057D03*
X164057D03*
X154057D03*
X149057D03*
X159057D03*
X169057D03*
X179057D03*
X189057D03*
X199057D03*
X209057D03*
X274057D03*
X264057D03*
X254057D03*
X244057D03*
X234057D03*
X224057D03*
X214057D03*
X219057D03*
X229057D03*
X239057D03*
X249057D03*
X259057D03*
X269057D03*
X315120Y8500D03*
X310120D03*
X305120D03*
X300120D03*
X296020Y9420D03*
Y14420D03*
Y19420D03*
Y24420D03*
Y29420D03*
X305862Y210014D03*
X334057Y755280D03*
X324057D03*
X314057D03*
X304057D03*
X294057D03*
X284057D03*
X279057D03*
X289057D03*
X299057D03*
X309057D03*
X319057D03*
X329057D03*
X339057D03*
X381638D03*
X384809Y752321D03*
X387045Y747849D03*
X389281Y743376D03*
X391517Y738904D03*
X393753Y734432D03*
X395989Y729960D03*
X398225Y725488D03*
X344057Y755280D03*
X600900Y29700D03*
X576610Y388416D03*
Y393416D03*
Y398416D03*
Y403416D03*
Y408416D03*
Y413416D03*
Y418416D03*
Y423416D03*
Y428416D03*
Y433416D03*
Y438416D03*
Y443416D03*
Y448416D03*
Y453416D03*
Y458416D03*
Y463416D03*
Y468416D03*
Y473416D03*
Y478416D03*
Y483416D03*
Y488416D03*
Y493416D03*
Y498416D03*
Y503416D03*
Y508416D03*
Y513416D03*
Y518416D03*
Y523416D03*
Y528416D03*
Y533416D03*
Y538416D03*
Y543416D03*
Y548416D03*
Y553416D03*
Y558416D03*
Y563416D03*
Y568416D03*
Y573416D03*
Y578416D03*
Y583416D03*
Y588416D03*
Y593416D03*
Y598416D03*
Y603416D03*
Y608416D03*
Y613416D03*
Y618416D03*
Y623416D03*
Y628416D03*
Y633416D03*
Y638416D03*
Y643416D03*
Y648416D03*
Y653416D03*
Y658416D03*
Y663416D03*
Y668416D03*
Y673416D03*
Y678416D03*
Y683416D03*
Y688416D03*
Y693416D03*
Y698416D03*
Y703416D03*
Y708416D03*
Y713416D03*
Y718416D03*
X577063Y723309D03*
X579299Y727781D03*
X581535Y732253D03*
X583771Y736725D03*
X586007Y741198D03*
X588243Y745670D03*
X590479Y750142D03*
X592715Y754614D03*
X609200Y330400D03*
X659722Y755280D03*
X649722D03*
X639722D03*
X634722D03*
X644722D03*
X654722D03*
X664722D03*
X671000Y421000D03*
X687015Y643700D03*
X729722Y755280D03*
X719722D03*
X709722D03*
X699722D03*
X689722D03*
X679722D03*
X669722D03*
X674722D03*
X684722D03*
X694722D03*
X704722D03*
X714722D03*
X724722D03*
X734722D03*
X780100Y8500D03*
X775100D03*
X770100D03*
X765100D03*
X760100D03*
X755100D03*
X750100D03*
X745100D03*
X787895D03*
X797895D03*
X792895D03*
X754000Y172700D03*
Y177500D03*
X798359Y351659D03*
X795193Y355540D03*
X791786Y359001D03*
X799722Y755280D03*
X789722D03*
X779722D03*
X769722D03*
X759722D03*
X749722D03*
X739722D03*
X744722D03*
X754722D03*
X764722D03*
X774722D03*
X784722D03*
X794722D03*
X807895Y8500D03*
X817895D03*
X827895D03*
X837895D03*
X847895D03*
X857895D03*
X862895D03*
X852895D03*
X842895D03*
X832895D03*
X822895D03*
X812895D03*
X802895D03*
X826993Y358840D03*
X821502Y358356D03*
X827145Y363638D03*
X821653Y363488D03*
X826900Y332500D03*
X825300Y339900D03*
X825100Y347300D03*
X828100Y352900D03*
X809792Y379122D03*
X814592D03*
X809792Y374322D03*
X814592D03*
X842900Y347200D03*
X840800Y352800D03*
X804300Y436500D03*
X843900Y464000D03*
X848700Y465200D03*
Y470600D03*
X849722Y755280D03*
X839722D03*
X829722D03*
X819722D03*
X809722D03*
X804722D03*
X814722D03*
X824722D03*
X834722D03*
X844722D03*
X854722D03*
X867895Y8500D03*
X877895D03*
X887895D03*
X897895D03*
X907895D03*
X916697Y19698D03*
Y29698D03*
Y39698D03*
Y49698D03*
Y59698D03*
Y69698D03*
Y64698D03*
Y54698D03*
Y44698D03*
Y34698D03*
Y24698D03*
Y14698D03*
X912895Y8500D03*
X902895D03*
X892895D03*
X882895D03*
X872895D03*
X916697Y79698D03*
Y89698D03*
Y99698D03*
Y109698D03*
Y119698D03*
Y129698D03*
Y134698D03*
Y124698D03*
Y114698D03*
Y104698D03*
Y94698D03*
Y84698D03*
Y74698D03*
Y139698D03*
Y149698D03*
Y159698D03*
Y169698D03*
Y179698D03*
Y189698D03*
Y199698D03*
Y194698D03*
Y184698D03*
Y174698D03*
Y164698D03*
Y154698D03*
Y144698D03*
Y209698D03*
Y219698D03*
Y229698D03*
Y239698D03*
Y249698D03*
Y259698D03*
Y264698D03*
Y254698D03*
Y244698D03*
Y234698D03*
Y224698D03*
Y214698D03*
Y204698D03*
Y269698D03*
Y279698D03*
Y289698D03*
Y299698D03*
Y309698D03*
Y319698D03*
Y329698D03*
Y324698D03*
Y314698D03*
Y304698D03*
Y294698D03*
Y284698D03*
Y274698D03*
Y339698D03*
Y349698D03*
Y359698D03*
Y369698D03*
Y379698D03*
Y389698D03*
Y394698D03*
Y384698D03*
Y374698D03*
Y364698D03*
Y354698D03*
Y344698D03*
Y334698D03*
Y399698D03*
Y409698D03*
Y419698D03*
Y429698D03*
Y439698D03*
Y449698D03*
Y459698D03*
Y454698D03*
Y444698D03*
Y434698D03*
Y424698D03*
Y414698D03*
Y404698D03*
Y469698D03*
Y479698D03*
Y489698D03*
Y499698D03*
Y509698D03*
Y519698D03*
Y524698D03*
Y514698D03*
Y504698D03*
Y494698D03*
Y484698D03*
Y474698D03*
Y464698D03*
Y529698D03*
Y539698D03*
Y549698D03*
Y559698D03*
Y569698D03*
Y579698D03*
Y589698D03*
Y584698D03*
Y574698D03*
Y564698D03*
Y554698D03*
Y544698D03*
Y534698D03*
Y599698D03*
Y609698D03*
Y619698D03*
Y629698D03*
Y639698D03*
Y649698D03*
Y659698D03*
Y654698D03*
Y644698D03*
Y634698D03*
Y624698D03*
Y614698D03*
Y604698D03*
Y594698D03*
Y669698D03*
Y679698D03*
Y689698D03*
Y699698D03*
Y709698D03*
Y719698D03*
Y714698D03*
Y704698D03*
Y694698D03*
Y684698D03*
Y674698D03*
Y664698D03*
X914700Y726100D03*
X912436Y730603D03*
X910200Y735300D03*
X907564Y739747D03*
X905500Y744400D03*
X903192Y748791D03*
X900800Y753700D03*
X894722Y755280D03*
G54D20*
G01X148409Y575672D02*
G03X146542Y577006I-1867J-639D01*
G01X138204D01*
G02X134173Y578675I-1J5700D01*
G01X132940Y579908D01*
G03X130906Y580750I-2033J-2033D01*
G01X106694D01*
G03X105161Y580115I0J-2168D01*
G01X97193Y572147D01*
X96235Y571190D01*
G02X93776Y570171I-2460J2460D01*
G01X93061D01*
G03X92271Y569776I1J-990D01*
G02X91481Y569381I-791J595D01*
G01X90281D01*
G02X89491Y569776I1J990D01*
G03X88701Y570171I-791J-595D01*
G01X87501D01*
G03X86711Y569776I1J-990D01*
G02X85921Y569381I-791J595D01*
G01X84721D01*
G02X83931Y569776I1J990D01*
G03X83141Y570171I-791J-595D01*
G01X82580D01*
G03X81936Y569527I0J-644D01*
G01Y562222D01*
G02X76818I-2559J0D01*
G01Y572749D01*
G03X76437Y573669I-1302J0D01*
G01Y573668D01*
G03X75518Y574048I-919J-921D01*
G01X74737D01*
G03X73404Y573496I0J-1886D01*
G01X73355Y573447D01*
G03X72754Y571996I1451J-1451D01*
G01Y568569D01*
G03X73758Y567565I1004J0D01*
G01X74152D01*
G01X71002D02*
G03X71554Y568898I-1333J1333D01*
G01Y571996D01*
G02X72506Y574296I3252J1D01*
G01X72555Y574345D01*
G02X74737Y575248I2181J-2183D01*
G01X75518D01*
G02X77286Y574518I2J-2502D01*
G02X78018Y572748I-1770J-1768D01*
G01Y562222D01*
G03X80736I1359J0D01*
G01Y569527D01*
G02X82580Y571371I1844J0D01*
G01X93775D01*
G03X95386Y572039I-1J2279D01*
G01X104312Y580964D01*
G02X106693Y581950I2381J-2382D01*
G01X130906D01*
G02X133789Y580757I2J-4075D01*
G01X135022Y579524D01*
G03X138204Y578206I3182J3182D01*
G01X146542D01*
G03X148409Y579353I0J2093D01*
G01X130607Y569636D02*
G03X128977Y568006I0J-1630D01*
G01Y567721D01*
G02X127267Y566011I-1710J0D01*
G01X124344D01*
G02X121800Y568555I0J2544D01*
G01Y569027D01*
G03X120259Y570600I-1573J0D01*
G01X117070D01*
G03X115656Y570014I0J-1999D01*
G01X114033Y568391D01*
G02X112619Y567805I-1414J1413D01*
G01X108934D01*
G03X107520Y567219I0J-1999D01*
G01X99681Y559380D01*
G02X98267Y558794I-1414J1413D01*
G01X94044D01*
G03X93032Y558375I0J-1431D01*
G03X92756Y557612I914J-762D01*
G01Y557077D01*
G02X92174Y555672I-1987J0D01*
G02X90770Y555090I-1405J1405D01*
G01X88859D01*
X88009Y555940D01*
X87725D01*
X86750Y554965D01*
G01X126347Y569556D02*
G02X127777Y568126I0J-1430D01*
G01Y567721D01*
G02X127267Y567211I-510J0D01*
G01X124344D01*
G02X123000Y568555I0J1344D01*
G01Y569027D01*
G03X120283Y571800I-2774J0D01*
G01X117070D01*
G03X114807Y570863I-1J-3199D01*
G01X113184Y569240D01*
G02X112619Y569005I-566J564D01*
G01X108934D01*
G03X106671Y568068I-1J-3199D01*
G01X98832Y560229D01*
G02X98267Y559994I-566J564D01*
G01X94044D01*
G03X92146Y559186I-1J-2631D01*
G03X91556Y557612I1800J-1572D01*
G01Y557077D01*
G02X91325Y556521I-787J1D01*
G02X90769Y556290I-557J556D01*
G01X89357D01*
X88507Y557140D01*
X87725D01*
X86750Y558115D01*
G01Y586463D02*
X87490Y585723D01*
G03X88410Y585342I920J920D01*
G01X93871D01*
G03Y589401I0J2030D01*
G01X84327D01*
G02Y595186I0J2893D01*
G01X98948D01*
G02X101455Y593678I1J-2836D01*
G01X101454Y593677D01*
G02X101562Y593387I-1054J-557D01*
G03X103183Y592099I1621J376D01*
G03X104376Y592917I0J1279D01*
G03X104391Y592950I-460J229D01*
G01X104390D01*
G02X109696Y593215I2717J-1145D01*
G02X109769Y593056I-1126J-613D01*
G03X111186Y592132I1417J625D01*
G03X112628Y593237I0J1493D01*
G01X112629D01*
G02X115248Y595186I2544J-684D01*
G01X117291D01*
G03X119054Y595906I-1J2520D01*
G01X120289Y597141D01*
G02X124127Y598730I3838J-3841D01*
G01X138717D01*
G02X141290Y596157I0J-2573D01*
G01Y591123D01*
G03X142800Y589613I1510J0D01*
G01X143469D01*
G03X144876Y590854I0J1418D01*
G01Y587173D02*
G03X143470Y588413I-1406J-177D01*
G01X142800D01*
G02X140090Y591123I0J2710D01*
G01Y596157D01*
G03X138717Y597530I-1373J0D01*
G01X124128D01*
G03X121138Y596292I0J-4230D01*
G01X119899Y595053D01*
G02X117291Y593986I-2608J2654D01*
G01X115214D01*
G03X113788Y592925I-41J-1433D01*
G02X111186Y590932I-2602J702D01*
G02X108642Y592641I0J2748D01*
G03X105496Y592484I-1535J-836D01*
G02X103183Y590899I-2313J895D01*
G02X100393Y593116I0J2864D01*
G03X98948Y593986I-1445J-765D01*
G01X84327D01*
G03Y590601I0J-1692D01*
G01X93871D01*
G02Y584142I0J-3229D01*
G01X88410D01*
G03X86992Y583554I1J-2006D01*
G01X86750Y583313D01*
G54D11*
G01X-13131Y-65072D02*
Y-145072D01*
G01D02*
X1244069D01*
G01X-29131Y-65072D02*
Y-33072D01*
G01X-13131Y-65072D02*
X1244069D01*
G01X-13131Y-100572D02*
X1244069D01*
G01X-17131Y-49072D02*
G02I-12000J0D01*
G01X-22281D02*
G02I-6850J0D01*
G01X-13131D02*
X-45131D01*
G01X89070Y62600D02*
X81770Y55300D01*
X44678D01*
X44588Y55210D01*
X42432D01*
X42342Y55300D01*
X38630D01*
X38590Y55260D01*
G01X102250Y455000D02*
Y304052D01*
X68253Y270055D01*
Y221762D01*
X102500Y187515D01*
Y76030D01*
X89070Y62600D01*
G01X197243Y551970D02*
X200498D01*
X202695Y554167D01*
Y556073D01*
X201242Y557526D01*
Y567052D01*
X204398Y570208D01*
X215586D01*
X225749Y580371D01*
Y601089D01*
X227396Y602736D01*
Y611611D01*
X235363Y619578D01*
X256659D01*
X258333Y621252D01*
Y631643D01*
X247110Y642866D01*
X227984D01*
X222950Y647900D01*
G01X194093Y551970D02*
X197243D01*
G01X203400Y649600D02*
Y652800D01*
X206000Y655400D01*
Y660800D01*
X206300Y661100D01*
G01X221238Y620524D02*
X222058D01*
X224740Y617842D01*
Y604559D01*
X223908Y603727D01*
Y603164D01*
X222658Y601914D01*
Y586773D01*
X221685Y585800D01*
X220000D01*
G01X213800Y631200D02*
X216000Y629000D01*
Y615700D01*
X217700Y614000D01*
Y611341D01*
X212308Y605949D01*
G01X222950Y647900D02*
Y650500D01*
X222970Y650520D01*
Y672971D01*
X237600Y687601D01*
Y697101D01*
X254648Y714149D01*
Y745463D01*
G01X226471Y649129D02*
X237509Y660167D01*
Y674915D01*
G01X215606Y645806D02*
Y646684D01*
X213200Y649090D01*
Y690442D01*
X214300Y691542D01*
Y695065D01*
X214270Y695095D01*
G01X268384Y662909D02*
X263800Y667493D01*
Y677000D01*
X266200Y679400D01*
G01X311715Y20397D02*
X302720Y29392D01*
Y32926D01*
X298854Y36792D01*
Y164041D01*
X313231Y178418D01*
Y188369D01*
X309400Y192200D01*
Y208000D01*
X307386Y210014D01*
X305862D01*
G01X352279Y580294D02*
Y588570D01*
X353347Y589638D01*
Y594371D01*
X356100Y597124D01*
Y626778D01*
X345700Y637178D01*
Y639133D01*
X343200Y641633D01*
Y643416D01*
X342650Y643966D01*
Y651184D01*
X336666Y657168D01*
Y663234D01*
X335750Y664150D01*
Y664700D01*
G01X288700Y667900D02*
X295900Y675100D01*
Y690430D01*
X287820Y698510D01*
Y718423D01*
X292600Y723203D01*
Y732320D01*
X287620Y737300D01*
G01X456569Y-65072D02*
Y-145072D01*
G01X594069Y-65072D02*
Y-145072D01*
G01X600900Y29700D02*
Y18498D01*
X605198Y14200D01*
X731910D01*
X736803Y19093D01*
Y52087D01*
G01X596489Y14110D02*
Y22401D01*
X580600Y38290D01*
Y73022D01*
X581550Y73972D01*
Y83000D01*
X592200Y93650D01*
Y174720D01*
X600723Y183243D01*
Y321923D01*
X609200Y330400D01*
G01X615150Y364200D02*
Y363408D01*
X621600Y356958D01*
Y341704D01*
X618007Y338111D01*
X611126D01*
X597223Y324208D01*
Y184693D01*
X588700Y176170D01*
Y96550D01*
X574500Y82350D01*
Y74100D01*
X576250Y72350D01*
Y43500D01*
X575550Y42800D01*
G01X584550Y80750D02*
X595700Y91900D01*
Y173270D01*
X619980Y197550D01*
G01X609240Y370337D02*
Y367059D01*
X611650Y364649D01*
Y361958D01*
X616700Y356908D01*
Y343200D01*
X616900Y343000D01*
G01X636963Y405999D02*
X635327D01*
X609240Y379912D01*
Y370337D01*
G01X632180Y397968D02*
Y396680D01*
X622794Y387294D01*
Y377894D01*
X615150Y370250D01*
Y364200D01*
G01X671000Y421000D02*
Y417757D01*
X659243Y406000D01*
X636966D01*
X636965Y405999D01*
X636963D01*
G01X632180Y397968D02*
X657858D01*
X679000Y419110D01*
Y442400D01*
X669500Y451900D01*
Y504100D01*
X672500Y507100D01*
G01X709069Y-65072D02*
Y-145072D01*
G01X690579Y299964D02*
X700579Y289964D01*
X708133D01*
X710469Y292300D01*
G01X795922Y531500D02*
Y545878D01*
X698100Y643700D01*
X687015D01*
G01X756431Y54010D02*
X754300Y56141D01*
Y90850D01*
X763882Y100432D01*
X779932D01*
X781250Y101750D01*
G01X803000Y117100D02*
X779800Y93900D01*
X762900D01*
X758600Y89600D01*
Y61300D01*
X760571Y59329D01*
Y53231D01*
X760200Y52860D01*
Y52600D01*
X754760Y47160D01*
X746540D01*
X746500Y47200D01*
G01X777967Y262576D02*
X778344D01*
X781600Y259320D01*
Y251800D01*
X783400Y250000D01*
X785600D01*
X790400Y245200D01*
Y240155D01*
X788200Y237955D01*
Y228700D01*
X792500Y224400D01*
X808812D01*
X814262Y218950D01*
G01X795593Y206063D02*
X789864Y211792D01*
X784108D01*
X780550Y215350D01*
X776640D01*
X772160Y219830D01*
Y233210D01*
X774700Y235750D01*
Y239050D01*
X777953Y242303D01*
Y256300D01*
G01X781300Y207800D02*
X780090Y206590D01*
X768940D01*
X767000Y208530D01*
Y213464D01*
X766104Y214360D01*
Y217654D01*
X768700Y220250D01*
Y238500D01*
X774803Y244603D01*
Y265749D01*
G01X804300Y436500D02*
X794199Y446601D01*
Y467801D01*
X759200Y502800D01*
Y508000D01*
G01X876569Y-65072D02*
Y-145072D01*
G01X1046569Y-65072D02*
Y-145072D01*
G01X1244069Y-65072D02*
Y-145072D01*
G01X1272069Y-49072D02*
G02I-12000J0D01*
G01X1266919D02*
G02I-6850J0D01*
G01X1276069D02*
X1244069D01*
G01X1260069Y-65072D02*
Y-33072D01*
X38590Y55260D03*
X30270Y48330D03*
X49600Y496050D03*
X55300Y495600D03*
X74152Y567565D03*
X71002D03*
X74152Y580163D03*
Y577013D03*
X53302Y567317D03*
X59200Y582200D03*
X38550Y617950D03*
X97600Y54810D03*
X89070Y62600D03*
X114390Y453185D03*
X102250Y455000D03*
X108300Y435900D03*
X138900Y525999D03*
X135012Y510200D03*
X119400Y511500D03*
X138000Y485900D03*
X116500Y477000D03*
X101800Y493000D03*
X81276Y548766D03*
X119605Y548705D03*
X86750Y539218D03*
X83600Y545518D03*
X89899D03*
Y539218D03*
X117200Y546300D03*
X83600Y539219D03*
X86750Y545518D03*
X122600Y557480D03*
X86750Y554965D03*
X130607Y569636D03*
X86750Y558115D03*
X126347Y569556D03*
X83600Y551817D03*
X117400Y567650D03*
X86750Y586463D03*
Y583313D03*
X83601Y580164D03*
X83600Y564415D03*
X86750D03*
X96570Y581730D03*
X86750Y551815D03*
X133800Y528500D03*
X123200Y534600D03*
X143500Y529000D03*
X93744Y542019D03*
X96371Y534124D03*
X93053Y606734D03*
X142447Y611714D03*
X98200Y616900D03*
X129800Y630700D03*
X116200Y611600D03*
X116023Y607423D03*
X119400Y614100D03*
X116500Y621000D03*
X116400Y616900D03*
X138500Y637900D03*
X130500Y638600D03*
X134700D03*
X129903Y634500D03*
X197085Y459899D03*
X190278Y459865D03*
X193686Y459799D03*
X176000Y460200D03*
X172200Y460100D03*
X157496Y461248D03*
X166600Y509800D03*
X187000Y499500D03*
X146500Y492500D03*
X176100Y473200D03*
X174700Y513900D03*
X182300Y509600D03*
X184780Y526990D03*
X178869Y509793D03*
X205447Y487762D03*
X158290Y502380D03*
X182874Y523590D03*
X170700Y509800D03*
X165900Y524100D03*
X172100Y467300D03*
X176800Y492200D03*
X175805Y524073D03*
X206180Y509524D03*
X200100Y491700D03*
X196243Y486782D03*
X155540Y506510D03*
X195300Y498900D03*
X195379Y510158D03*
X150162Y525937D03*
X148527Y519491D03*
X191725Y523074D03*
X148409Y575672D03*
X144876Y590854D03*
X148409Y579353D03*
X144876Y587173D03*
X184830Y529960D03*
X149419Y535654D03*
X199400Y529400D03*
X208000Y529300D03*
X149242Y531080D03*
X194490Y645390D03*
X178140Y630330D03*
X209093Y615849D03*
X195900Y649350D03*
X203400Y649600D03*
X180700Y640460D03*
X177300Y626800D03*
X204150Y645180D03*
X199600Y650100D03*
X192960Y628510D03*
X187900Y628500D03*
X162100Y711215D03*
X200400Y694700D03*
X206300Y661100D03*
X185100Y705600D03*
X184800Y709300D03*
X275100Y460300D03*
X268900Y445150D03*
X244700Y451200D03*
X236100Y445100D03*
X239300Y443800D03*
X243000D03*
X247900Y445300D03*
X260600Y442600D03*
X250500Y451300D03*
X232200Y445600D03*
X261200Y525400D03*
X258100Y516400D03*
X258381Y509498D03*
X225914Y523051D03*
X231800Y512100D03*
X223600Y512400D03*
X238400Y511300D03*
X265274Y509512D03*
X267800Y479900D03*
X260741Y542700D03*
X228800Y542100D03*
X228313Y552169D03*
X261308Y583388D03*
X237100Y590000D03*
X257700Y586400D03*
X261500Y576400D03*
X257891Y563786D03*
X233607Y557671D03*
X232400Y533200D03*
X267957Y537304D03*
X274623Y578896D03*
X271357Y537253D03*
X213800Y631200D03*
X212308Y605949D03*
X266571Y608619D03*
X275470Y608480D03*
X270400Y622870D03*
X222950Y647900D03*
X226471Y649129D03*
X243322Y597509D03*
X215606Y645806D03*
X229500Y631500D03*
X212900Y619201D03*
X273714Y629870D03*
X221238Y620524D03*
X234205Y598743D03*
X233258Y595693D03*
X232130Y612950D03*
X251900Y609600D03*
X255733Y622329D03*
X237509Y674915D03*
X266200Y679400D03*
X268384Y662909D03*
X264700Y700000D03*
X214270Y695095D03*
X275300Y668749D03*
X239400Y677900D03*
X266300Y692574D03*
X254648Y745463D03*
X311715Y20397D03*
X310353Y62159D03*
X337808Y288709D03*
X314000Y390500D03*
X281200Y453500D03*
X333850Y458400D03*
X286700Y457500D03*
X323759Y435145D03*
X327159Y435201D03*
X276634Y498311D03*
X308687Y519193D03*
X302307Y505799D03*
X298907Y505851D03*
X292100Y516000D03*
X297400Y517981D03*
X325400Y505800D03*
X282403Y474500D03*
X282400Y470200D03*
X328200Y511600D03*
X331200Y508900D03*
X277603Y479948D03*
X278400Y463300D03*
X334650Y508900D03*
X323659Y557310D03*
X334900Y586100D03*
X333512Y553888D03*
X324200Y565300D03*
X337300Y583000D03*
X336367Y549943D03*
X277048Y590470D03*
X318736Y549697D03*
X280100Y532100D03*
X279664Y535473D03*
X337346Y545100D03*
X341316Y545000D03*
X282000Y583500D03*
X298514Y550184D03*
X293087Y530571D03*
X276839Y582309D03*
X340100Y631417D03*
X325300Y648700D03*
X294500Y630600D03*
X298100Y630650D03*
X330400Y644300D03*
X334700Y644500D03*
X335100Y650600D03*
X338100Y635800D03*
X331718Y655832D03*
X329100Y650700D03*
X317689Y599833D03*
X287200Y632600D03*
X290900Y630900D03*
X278769Y700697D03*
X335750Y664700D03*
X288700Y667900D03*
X340100Y718200D03*
X327250Y701500D03*
X327162Y696776D03*
X276800Y697925D03*
X339804Y679030D03*
X289700Y678830D03*
X280646Y717540D03*
X304700Y668500D03*
X287620Y737300D03*
X290000Y727000D03*
X354798Y22452D03*
X386759Y79693D03*
X390456D03*
X381269Y94981D03*
X384666Y93741D03*
X390964Y87226D03*
X388700Y89800D03*
X370149Y167337D03*
X370882Y163688D03*
X404727Y162141D03*
X392102Y175384D03*
X392458Y171676D03*
X400430Y147190D03*
X396561Y351418D03*
X378492Y378175D03*
X367358Y372531D03*
X367471Y369120D03*
X350491Y453809D03*
X387450Y454558D03*
X387396Y458126D03*
X384395Y449114D03*
X374700Y460300D03*
X346500Y435200D03*
X355400Y453800D03*
X357900Y450800D03*
X363500Y464700D03*
X384849Y525499D03*
Y521681D03*
X400080Y519500D03*
X381986Y515631D03*
X374751Y485636D03*
X374715Y498722D03*
X390229Y508189D03*
X389288Y483500D03*
X373800Y503000D03*
X378267Y496100D03*
X352279Y580294D03*
X346303Y591947D03*
X369500Y542900D03*
X388641Y549747D03*
X400093Y536351D03*
X399726Y562327D03*
X399946Y558677D03*
X344163Y553395D03*
X345259Y557566D03*
X391993Y582154D03*
X372939Y559838D03*
X346590Y572090D03*
X350278Y572306D03*
X341493Y541250D03*
X393912Y578705D03*
X355000Y652160D03*
X374200Y645871D03*
X364014Y593996D03*
X343797Y631417D03*
X384300Y619925D03*
X396166Y692630D03*
X343200Y667600D03*
X389999Y664697D03*
X367700Y685450D03*
X343338Y679236D03*
X399999Y673422D03*
X396419Y679708D03*
X382308Y665022D03*
X396419Y686586D03*
X346600Y714500D03*
X346000Y684300D03*
X380387Y685261D03*
X392500Y673500D03*
X378595Y664960D03*
X388626Y715509D03*
X392500Y692500D03*
X396419Y683186D03*
X461736Y111300D03*
X524950Y16120D03*
X481800Y71200D03*
X596489Y14110D03*
X575550Y42800D03*
X601311Y13521D03*
X545200Y69000D03*
X596300Y66950D03*
X597950Y58950D03*
X584550Y80750D03*
X559900Y88400D03*
X563268Y88872D03*
X540179Y111036D03*
X539346Y114333D03*
X599682Y103715D03*
X562160Y178600D03*
X602075Y339970D03*
X586155Y393023D03*
X593064Y400910D03*
X593229Y397308D03*
X665800Y7550D03*
X666400Y22200D03*
X619980Y197550D03*
X630800Y147600D03*
X634800Y147700D03*
X640400Y217600D03*
X636491Y217592D03*
X633092Y217496D03*
X659500Y205300D03*
X662900D03*
X645400Y264050D03*
X620160Y203500D03*
X660700Y292200D03*
X634830Y292095D03*
X638453Y291949D03*
X638603Y296320D03*
X642003Y296249D03*
X645403Y296229D03*
X631069Y292512D03*
X654600Y367600D03*
X639318Y354003D03*
X643082Y353941D03*
X659300Y373100D03*
X607800Y382362D03*
X607100Y351200D03*
X605400Y393400D03*
X609240Y370337D03*
X616900Y343000D03*
X615150Y364200D03*
X640968Y370425D03*
X636963Y405999D03*
X632180Y397968D03*
X616160Y542700D03*
X614000Y561250D03*
X606600Y551100D03*
X718098Y259423D03*
X693800Y264300D03*
X709079Y229564D03*
X703979Y219995D03*
X730709Y215355D03*
X732264Y204312D03*
X703320Y203900D03*
X733859Y212206D03*
X722468Y308964D03*
X733859Y272048D03*
X690579Y299964D03*
X675555Y318736D03*
X672350Y317600D03*
X716300Y331340D03*
X712410Y331320D03*
X718300Y362900D03*
X722500Y353000D03*
X718000D03*
X713500Y362900D03*
X709006Y410206D03*
X721504Y402321D03*
X699900Y453600D03*
X691813Y407210D03*
X691874Y410741D03*
X691873Y403800D03*
X690300Y460200D03*
X696800Y476400D03*
X689100Y507900D03*
X672500Y507100D03*
X725000Y576100D03*
X710100Y545600D03*
X717450Y551554D03*
X702515Y597064D03*
X703800Y608400D03*
X712708Y603038D03*
X756431Y54010D03*
X736803Y52087D03*
X746500Y47200D03*
X780815Y47062D03*
X762765Y42200D03*
X781250Y101750D03*
X762000Y113000D03*
X763825Y89975D03*
X776500Y82700D03*
X750500Y118500D03*
X750600Y114200D03*
X769500Y91000D03*
X792600Y101300D03*
X749900Y185200D03*
X786343Y179959D03*
X745700Y185900D03*
X769100Y187800D03*
X786388Y183429D03*
X772810Y179901D03*
X772700Y183300D03*
X777967Y262576D03*
X795593Y206063D03*
X777953Y256300D03*
X781300Y207800D03*
X774803Y265749D03*
X740158Y215355D03*
X743008Y206059D03*
X793701Y234254D03*
X793672Y240560D03*
X796821Y246859D03*
X793701Y227954D03*
X744881Y309000D03*
X796839Y290934D03*
X796832Y272064D03*
X796875Y304331D03*
X796862Y281522D03*
X787426Y272060D03*
X790551Y278384D03*
X737009Y284646D03*
X744400Y322800D03*
X746456Y297243D03*
X765353Y287794D03*
X771653D03*
X777952D03*
X784251D03*
X762225Y297227D03*
X755898Y287804D03*
X790357Y377781D03*
X735300Y401957D03*
X759200Y508000D03*
X781700Y510900D03*
X795922Y531500D03*
X747200Y611900D03*
X803000Y117100D03*
X821962Y189277D03*
X801385Y183067D03*
X801340Y179597D03*
X831504Y199129D03*
X832148Y204444D03*
X807177Y261023D03*
X814262Y218950D03*
X826000Y233400D03*
X828000Y243100D03*
X810079Y271264D03*
X809968Y290464D03*
X808400Y300900D03*
X812164Y279674D03*
X850950Y489300D03*
X888551Y226649D03*
X892449Y241249D03*
X886540Y388996D03*
G54D21*
G01X30270Y48330D02*
X30690Y48750D01*
X98341D01*
X106750Y57159D01*
Y167350D01*
X107926Y168526D01*
Y435526D01*
X108300Y435900D01*
G01X38550Y617950D02*
X37650Y617050D01*
Y572550D01*
X40225Y569975D01*
Y517675D01*
X44050Y513850D01*
Y501600D01*
X49600Y496050D01*
G01X101800Y493000D02*
X99400Y490600D01*
X83771D01*
X75471Y498900D01*
X58400D01*
X51175Y506125D01*
Y511676D01*
X43725Y519126D01*
Y563516D01*
X47300Y567091D01*
Y585850D01*
X78350Y616900D01*
X98200D01*
G01X129800Y630700D02*
X97240D01*
X85745Y619205D01*
X69462D01*
X45300Y595043D01*
Y567920D01*
X41725Y564345D01*
Y518297D01*
X46661Y513361D01*
Y503739D01*
X54800Y495600D01*
X55300D01*
G01X159449Y586614D02*
X157590Y588473D01*
Y589850D01*
X153110Y594330D01*
Y596220D01*
X150370Y598960D01*
X149424D01*
X143614Y604770D01*
X117045D01*
X115425Y603150D01*
X77822D01*
X70720Y596048D01*
Y582940D01*
X73497Y580163D01*
X74152D01*
G01Y577013D02*
Y577442D01*
X76040Y579330D01*
Y592291D01*
X82969Y599220D01*
X117240D01*
X119700Y601680D01*
X142028D01*
X148008Y595700D01*
X149580D01*
X153450Y591830D01*
Y587000D01*
X155910Y584540D01*
X160000D01*
X160526Y585066D01*
X162114D01*
G02X162995Y584966I0J-3931D01*
G03X165748Y586614I519J2257D01*
G01X114390Y453185D02*
X106425Y445220D01*
Y169147D01*
X105250Y167972D01*
Y62460D01*
X97600Y54810D01*
G01X150162Y525937D02*
Y524364D01*
X151982Y522544D01*
Y517591D01*
X148713Y514322D01*
Y500921D01*
X142522Y494730D01*
Y460378D01*
X150500Y452400D01*
X213100D01*
X219800Y445700D01*
G01X148527Y519491D02*
Y516876D01*
X144065Y512414D01*
Y498395D01*
X141022Y495352D01*
Y459756D01*
X150178Y450600D01*
X208500D01*
X213874Y445226D01*
G01X138000Y485900D02*
Y487100D01*
X139022Y488122D01*
Y508522D01*
X142065Y511565D01*
Y526735D01*
X139800Y529000D01*
X134300D01*
X133800Y528500D01*
G01X116500Y477000D02*
X120500Y481000D01*
Y500635D01*
X116500Y504635D01*
Y527600D01*
X123200Y534300D01*
Y534600D01*
G01X159449Y561417D02*
X154600D01*
X150600Y557417D01*
X136890D01*
X136390Y557917D01*
Y558917D01*
X136890Y559417D01*
X148890D01*
X149390Y559917D01*
Y560917D01*
X148890Y561417D01*
X117944D01*
X116884Y560357D01*
X112749D01*
X105737Y553345D01*
X103389D01*
X101131Y551087D01*
X96439D01*
X94995Y549643D01*
X82153D01*
X81276Y548766D01*
G01X91461Y540793D02*
X91885Y540369D01*
X95518D01*
X96166Y541017D01*
X108235D01*
X116084Y548866D01*
X119444D01*
X119605Y548705D01*
G01X172047Y561417D02*
X170497Y562967D01*
X161955D01*
X161048Y562060D01*
Y560823D01*
X160042Y559817D01*
X154710D01*
X153920Y559027D01*
Y556740D01*
X151510Y554330D01*
X134890D01*
X134390Y554830D01*
Y558860D01*
X133833Y559417D01*
X132168D01*
X131668Y558917D01*
Y554960D01*
X131168Y554460D01*
X130168D01*
X129668Y554960D01*
Y558917D01*
X129168Y559417D01*
X128168D01*
X127668Y558917D01*
Y557050D01*
X127168Y556550D01*
X126168D01*
X125668Y557050D01*
Y558917D01*
X125168Y559417D01*
X118773D01*
X117713Y558357D01*
X113578D01*
X106566Y551345D01*
X104218D01*
X101890Y549017D01*
X96166D01*
X95892Y548743D01*
X86825D01*
X83600Y545518D01*
G01X89899D02*
X90874Y544543D01*
X95812D01*
X96286Y545017D01*
X106577D01*
X114920Y553360D01*
X124445D01*
X125570Y552235D01*
X127254D01*
X127754Y551735D01*
Y550180D01*
X128254Y549680D01*
X129254D01*
X129754Y550180D01*
Y551735D01*
X130254Y552235D01*
X131254D01*
X131754Y551735D01*
Y550180D01*
X132254Y549680D01*
X133254D01*
X133754Y550180D01*
Y551735D01*
X134254Y552235D01*
X135254D01*
X135754Y551735D01*
Y549480D01*
X136254Y548980D01*
X137254D01*
X137754Y549480D01*
Y551735D01*
X138254Y552235D01*
X139254D01*
X139754Y551735D01*
Y548980D01*
X140254Y548480D01*
X141254D01*
X141754Y548980D01*
Y551735D01*
X142254Y552235D01*
X143254D01*
X143754Y551735D01*
Y548780D01*
X144254Y548280D01*
X145254D01*
X145754Y548780D01*
Y551735D01*
X146254Y552235D01*
X152464D01*
X158462Y558233D01*
X160262D01*
X161847Y559818D01*
X167348D01*
X168898Y558268D01*
G01X117200Y546300D02*
X109917Y539017D01*
X90100D01*
X89899Y539218D01*
G01X159449Y555118D02*
X159148D01*
X144280Y540250D01*
X130533D01*
X127300Y537017D01*
X125024D01*
X124524Y537517D01*
Y540050D01*
X124024Y540550D01*
X123024D01*
X122524Y540050D01*
Y536910D01*
X122024Y536410D01*
X121024D01*
X120524Y536910D01*
Y542310D01*
X120024Y542810D01*
X119024D01*
X118524Y542310D01*
Y534820D01*
X118024Y534320D01*
X117024D01*
X116524Y534820D01*
Y540790D01*
X116024Y541290D01*
X115024D01*
X114524Y540790D01*
Y537517D01*
X114024Y537017D01*
X93540D01*
X93284Y537273D01*
X85546D01*
X83600Y539219D01*
G01X107395Y549345D02*
X105047D01*
X102719Y547017D01*
X96731D01*
X95157Y545443D01*
X92308D01*
X90583Y547168D01*
X88400D01*
X86750Y545518D01*
G01X117400Y567650D02*
X114107Y564357D01*
X108449D01*
X99936Y555844D01*
X96166D01*
X95830Y555508D01*
X93428D01*
X91687Y553767D01*
G01X83601Y580164D02*
Y578720D01*
X82801Y577920D01*
X79736D01*
X78936Y578720D01*
Y587091D01*
X79736Y587891D01*
X82221D01*
X83021Y587091D01*
Y584549D01*
X86279Y581291D01*
X87878D01*
X88401Y581814D01*
X93986D01*
X96456Y579344D01*
X98444D01*
X104000Y584900D01*
X130202D01*
X130702Y585400D01*
Y588410D01*
X131202Y588910D01*
X133202D01*
X133702Y588410D01*
Y585400D01*
X134202Y584900D01*
X135774D01*
X138896Y581778D01*
X140468D01*
X141062Y581184D01*
X146434D01*
X147650Y582400D01*
X150600D01*
X151434Y581566D01*
X155195D01*
G02X156161Y581966I966J-966D01*
G01X160195D01*
G02X161478Y581434I-1J-1815D01*
G01X162598Y580315D01*
G01X91287Y562855D02*
X96905D01*
X106005Y571955D01*
X111646D01*
X114491Y574800D01*
X128860D01*
X133475Y570185D01*
Y567393D01*
X134268Y566600D01*
X139430D01*
X139930Y567100D01*
Y567636D01*
X142294Y570000D01*
X151680D01*
X152364Y569316D01*
X166846D01*
X167348Y569818D01*
Y577742D01*
X166360Y578730D01*
X159206D01*
G03X158035Y578245I0J-1656D01*
G01X157405Y577615D01*
G02X156319Y577165I-1086J1086D01*
G01X156299D01*
G01X159449Y580315D02*
G03X158026Y579725I1J-2013D01*
G01X157545Y579245D01*
X157036Y578736D01*
X151940D01*
X151440Y578236D01*
Y575940D01*
X151940Y575440D01*
X163460D01*
X163960Y574940D01*
Y572940D01*
X163460Y572440D01*
X154330D01*
X153330Y571440D01*
X143290D01*
X142660Y572070D01*
Y573193D01*
X141860Y573993D01*
X140114D01*
X139314Y573193D01*
Y571317D01*
X138814Y570817D01*
X136814D01*
X136314Y571317D01*
Y572362D01*
X130876Y577800D01*
X113248D01*
X110403Y574955D01*
X104731D01*
X95753Y565977D01*
X92377D01*
G01X96570Y581730D02*
X102740Y587900D01*
X127160D01*
X127660Y588400D01*
Y590400D01*
X127160Y590900D01*
X122970D01*
X122470Y591400D01*
Y593400D01*
X122970Y593900D01*
X135140D01*
X136800Y592240D01*
Y588659D01*
X140616Y584843D01*
X142532D01*
X143407Y583968D01*
X147108D01*
X147566Y584426D01*
Y593120D01*
X148066Y593620D01*
X150066D01*
X150566Y593120D01*
Y584344D01*
X151944Y582966D01*
X162100D01*
X162598Y583464D01*
G01X165748Y567717D02*
X164198Y566167D01*
X156943D01*
X155580Y567530D01*
X143080D01*
X142580Y567030D01*
Y566030D01*
X143080Y565530D01*
X153940D01*
X154440Y565030D01*
Y564030D01*
X153940Y563530D01*
X117228D01*
X116055Y562357D01*
X109278D01*
X107558Y560637D01*
Y559929D01*
X108135Y559352D01*
Y558644D01*
X107428Y557937D01*
X106720D01*
X106143Y558514D01*
X105435D01*
X100765Y553844D01*
X96166D01*
X96007Y554003D01*
X93893D01*
X91705Y551815D01*
X86750D01*
G01X162599Y548821D02*
X161046Y550374D01*
X156874D01*
X145378Y538878D01*
Y530878D01*
X143500Y529000D01*
G01X93744Y542019D02*
X95168D01*
X96166Y543017D01*
X107406D01*
X115749Y551360D01*
X121900D01*
X122400Y550860D01*
Y543280D01*
X123130Y542550D01*
X124853D01*
X126493Y540910D01*
X128364D01*
X129704Y542250D01*
X130906D01*
X131406Y542750D01*
Y544880D01*
X131906Y545380D01*
X132906D01*
X133406Y544880D01*
Y542750D01*
X133906Y542250D01*
X134906D01*
X135406Y542750D01*
Y545830D01*
X135906Y546330D01*
X136906D01*
X137406Y545830D01*
Y542750D01*
X137906Y542250D01*
X138906D01*
X139406Y542750D01*
Y545960D01*
X139906Y546460D01*
X140906D01*
X141406Y545960D01*
Y542750D01*
X141906Y542250D01*
X144078D01*
X158496Y556668D01*
X167349D01*
X168898Y555119D01*
G01X93053Y606734D02*
X94453Y608134D01*
X97017D01*
X97033Y608150D01*
X102167D01*
X102267Y608050D01*
X105367D01*
X107720Y610403D01*
X114779D01*
X115433Y609750D01*
X116967D01*
X117735Y610518D01*
X141251D01*
X142447Y611714D01*
G01X159448Y592913D02*
X158792Y593569D01*
X158476D01*
X156681Y595364D01*
Y597241D01*
X155829Y598093D01*
Y598884D01*
X150315Y604398D01*
Y606485D01*
X141850Y614950D01*
X122733D01*
X121250Y613467D01*
Y613333D01*
X119935Y612018D01*
X117113D01*
X116695Y611600D01*
X116200D01*
G01X116023Y607423D02*
Y607750D01*
X116523Y608250D01*
X117589D01*
X118179Y608840D01*
X126553D01*
X126593Y608880D01*
X144560D01*
X154929Y598511D01*
Y597720D01*
X155780Y596869D01*
Y594388D01*
X158805Y591363D01*
X160137D01*
X161736Y589764D01*
X162598D01*
G01X165748D02*
X164791D01*
X163241Y591314D01*
X162004D01*
X161000Y592318D01*
Y593520D01*
X160998Y593522D01*
Y593556D01*
X160084Y594470D01*
X158848D01*
X157814Y595504D01*
Y597381D01*
X156729Y598466D01*
Y599738D01*
X155760Y600708D01*
Y605040D01*
X154699Y606101D01*
Y606156D01*
X153792Y607063D01*
X153737D01*
X144210Y616590D01*
X128610D01*
X125790Y619410D01*
X122010D01*
X119400Y616800D01*
Y614100D01*
G01X165748Y596063D02*
X165048Y596763D01*
X164277D01*
X163377Y597663D01*
X161905D01*
X160998Y598570D01*
Y599856D01*
X159934Y600920D01*
Y604162D01*
X155600Y608496D01*
Y613000D01*
X146250Y622350D01*
X139910D01*
X137507Y624753D01*
X126245D01*
X124992Y623500D01*
X119000D01*
X116500Y621000D01*
G01X165748Y592913D02*
X165597D01*
X163997Y594513D01*
X161955D01*
X160998Y595470D01*
Y596706D01*
X160041Y597663D01*
X158805D01*
X157898Y598570D01*
Y598632D01*
X157630Y598900D01*
Y605193D01*
X154700Y608123D01*
Y609350D01*
X145460Y618590D01*
X129439D01*
X126529Y621500D01*
X121000D01*
X116400Y616900D01*
G01X138500Y637900D02*
X139300Y637100D01*
X156916D01*
X159050Y634967D01*
Y633550D01*
X166811Y625789D01*
X170333D01*
X176797Y619325D01*
Y598570D01*
X176796Y598569D01*
Y595421D01*
X177703Y594514D01*
X178939D01*
X180540Y592913D01*
X181497D01*
G01X130500Y638600D02*
X135500Y633600D01*
X153061D01*
X163872Y622789D01*
X169089D01*
X173600Y618278D01*
Y598617D01*
X175197Y597020D01*
Y596063D01*
G01X134700Y638600D02*
Y637600D01*
X137100Y635200D01*
X153583D01*
X164494Y624289D01*
X169711D01*
X175197Y618803D01*
Y599213D01*
G01X129903Y634500D02*
X132653Y631750D01*
X152750D01*
X163211Y621289D01*
X168467D01*
X172100Y617656D01*
Y615574D01*
X172670Y615004D01*
Y599835D01*
X172048Y599213D01*
G01X184830Y529960D02*
X186757Y528033D01*
Y523621D01*
X189250Y521128D01*
Y508121D01*
X193000Y504371D01*
Y479658D01*
X197085Y475573D01*
Y459899D01*
G01X190278Y459865D02*
Y476722D01*
X185200Y481800D01*
Y498050D01*
X184950Y498300D01*
Y503396D01*
X182874Y505472D01*
Y508926D01*
X182300Y509500D01*
Y509600D01*
G01X193686Y459799D02*
Y476143D01*
X187200Y482629D01*
Y488750D01*
X190950Y492500D01*
Y503054D01*
X187099Y506905D01*
Y510601D01*
X185317Y512383D01*
Y526453D01*
X184780Y526990D01*
G01X178869Y509793D02*
X180850Y507812D01*
Y465050D01*
X176000Y460200D01*
G01X176800Y492200D02*
X176756Y492244D01*
X176668D01*
X174750Y490326D01*
Y480021D01*
X172900Y478171D01*
Y473400D01*
X174400Y471900D01*
Y462300D01*
X172200Y460100D01*
G01X157496Y461248D02*
X162244Y456500D01*
X217700D01*
X234400Y439800D01*
X289735D01*
X305935Y423600D01*
X319980D01*
X326249Y417331D01*
Y409724D01*
X319862Y403337D01*
X312237D01*
X298179Y389279D01*
Y376000D01*
X301700Y372479D01*
Y194646D01*
X310481Y185865D01*
Y179558D01*
X296104Y165181D01*
Y35652D01*
X299970Y31786D01*
Y27930D01*
X315450Y12450D01*
X324642D01*
X330472Y6620D01*
X521945D01*
X523743Y6619D01*
X662252D01*
X665033Y9400D01*
X733122D01*
X741053Y17331D01*
Y85012D01*
X763790Y107749D01*
X764175D01*
X767251Y110825D01*
Y111210D01*
X779556Y123515D01*
X782237D01*
X874940Y216218D01*
Y317136D01*
X882250Y324446D01*
Y384706D01*
X886540Y388996D01*
G01X166600Y509800D02*
X164750Y511650D01*
Y517399D01*
X170100Y522749D01*
Y531300D01*
X171350Y532550D01*
Y539823D01*
X170373Y540800D01*
G01X187000Y499500D02*
Y504175D01*
X184874Y506301D01*
Y509855D01*
X183129Y511600D01*
X182248D01*
X181024Y512824D01*
Y518276D01*
X180600Y518700D01*
Y540321D01*
X180021Y540900D01*
G01X146500Y492500D02*
Y493207D01*
X157390Y504097D01*
Y508530D01*
X160250Y511390D01*
Y519556D01*
X159449Y520357D01*
Y542521D01*
G01X174700Y513900D02*
X174715Y513885D01*
Y503767D01*
X177000Y501482D01*
Y495117D01*
X178800Y493317D01*
Y477200D01*
X176100Y474500D01*
Y473200D01*
G01X178869Y509793D02*
X177019Y511643D01*
Y518700D01*
X178300Y519981D01*
Y527029D01*
X178785Y527514D01*
Y543062D01*
X181394Y545671D01*
X181497D01*
G01X205447Y487762D02*
Y495547D01*
X209842Y499942D01*
Y545669D01*
G01X165749Y548819D02*
Y547949D01*
X164149Y546349D01*
Y544849D01*
X163369Y544069D01*
X161956D01*
X161049Y543162D01*
Y522384D01*
X162140Y521293D01*
Y506230D01*
X158290Y502380D01*
G01X181496Y542520D02*
Y541204D01*
X182800Y539900D01*
Y523664D01*
X182874Y523590D01*
G01X173522Y541100D02*
Y532122D01*
X172100Y530700D01*
Y521920D01*
X168850Y518670D01*
Y511850D01*
X170700Y510000D01*
Y509800D01*
G01X165900Y524100D02*
X165850Y524150D01*
Y529350D01*
X164199Y531001D01*
Y543162D01*
X165137Y544100D01*
X166373D01*
X167348Y545075D01*
Y550248D01*
G01X172100Y467300D02*
X170900Y468500D01*
Y479000D01*
X172750Y480850D01*
Y500867D01*
X172715Y500902D01*
Y519706D01*
X174100Y521091D01*
Y523739D01*
X173450Y524389D01*
Y529784D01*
X176747Y533081D01*
Y546264D01*
X177754Y547271D01*
X179947D01*
X181497Y548821D01*
G01X178346Y545670D02*
X177800Y545124D01*
Y528800D01*
X176300Y527300D01*
Y524568D01*
X175805Y524073D01*
G01X206180Y509524D02*
X205350Y510354D01*
Y533950D01*
X204900Y534400D01*
Y542915D01*
X205185Y543200D01*
G01X200100Y491700D02*
Y504000D01*
X201150Y505050D01*
Y515750D01*
X199400Y517500D01*
Y529400D01*
G01X196243Y486782D02*
X201432D01*
X201950Y487300D01*
Y500550D01*
X208030Y506630D01*
Y510291D01*
X208000Y510321D01*
Y529300D01*
G01X149242Y531080D02*
X153297D01*
X155097Y532880D01*
X156770D01*
X157580Y532070D01*
Y518945D01*
X153151Y514516D01*
Y508899D01*
X155540Y506510D01*
G01X195300Y498900D02*
Y504900D01*
X193300Y506900D01*
Y512983D01*
X193299Y512984D01*
Y514518D01*
X193900Y515119D01*
Y528466D01*
X193650Y528716D01*
Y530084D01*
X193900Y530334D01*
Y535500D01*
X195644Y537244D01*
Y544069D01*
X197244Y545669D01*
G01X195379Y510158D02*
X196999Y511778D01*
Y537040D01*
X197525Y537566D01*
G01X156300Y539371D02*
X157899Y540970D01*
Y546314D01*
X158806Y547221D01*
X163244D01*
X164199Y548176D01*
Y551324D01*
X164198Y551325D01*
Y552611D01*
X165107Y553520D01*
X182607D01*
X186851Y549276D01*
Y532457D01*
X188938Y530370D01*
Y524825D01*
X190397Y523366D01*
X191433D01*
X191725Y523074D01*
G01X167791Y581867D02*
X170004D01*
G01X170005Y585061D02*
X168316D01*
G01X167301Y587721D02*
Y586032D01*
G01X149419Y535654D02*
Y540984D01*
X155656Y547221D01*
X156816D01*
X158416Y548821D01*
X159449D01*
G01X204164Y585064D02*
X204185D01*
G01X203486Y581914D02*
X218764D01*
X220000Y583150D01*
Y585800D01*
G01X205142Y584108D02*
X206049Y585015D01*
X217265D01*
X218050Y585800D01*
X220000D01*
G01X204185Y585064D02*
X205092Y585971D01*
Y587207D01*
X206095Y588210D01*
X219390D01*
X220000Y587600D01*
Y585800D01*
G01X255733Y622329D02*
X254582Y623480D01*
X220230D01*
X219050Y622300D01*
Y618050D01*
X220750Y616350D01*
Y610200D01*
X218521Y607971D01*
Y598321D01*
X214663Y594463D01*
X209198D01*
X208242Y593507D01*
Y592104D01*
X207500Y591362D01*
X201944D01*
X200393Y592913D01*
G01X184645Y599213D02*
Y619365D01*
X179326Y624684D01*
Y629144D01*
X178140Y630330D01*
G01X209093Y615849D02*
X207390Y614146D01*
Y605253D01*
X205142Y603005D01*
Y601129D01*
X204242Y600229D01*
Y599913D01*
X203542Y599213D01*
G01X206692Y602362D02*
Y602992D01*
X208290Y604590D01*
Y609106D01*
X211050Y611866D01*
Y626106D01*
X210350Y626806D01*
Y632465D01*
X212135Y634250D01*
X215064D01*
X216004Y633310D01*
X227690D01*
X229500Y631500D01*
G01X212900Y619201D02*
Y610187D01*
X209991Y607278D01*
Y604930D01*
X208242Y603181D01*
Y598570D01*
X207285Y597613D01*
X206049D01*
X204499Y596063D01*
X203542D01*
G01X180700Y640460D02*
X173950Y633710D01*
Y624294D01*
X178347Y619897D01*
Y599213D01*
G01X177300Y626800D02*
Y623900D01*
X181496Y619704D01*
Y596062D01*
G01X204150Y645180D02*
Y643650D01*
X206840Y640960D01*
Y628470D01*
X197950Y619580D01*
Y609850D01*
X199893Y607907D01*
Y600133D01*
X198843Y599083D01*
Y595420D01*
X199750Y594513D01*
X207335D01*
X208291Y595469D01*
Y596706D01*
X209841Y598256D01*
Y599212D01*
G01X199600Y650100D02*
Y648250D01*
X200720Y647130D01*
X204820D01*
X205250Y647560D01*
X208590D01*
X209750Y646400D01*
Y643280D01*
X208700Y642230D01*
Y628208D01*
X206300Y625808D01*
Y625785D01*
X202792Y622277D01*
Y606830D01*
X201992Y606030D01*
Y598570D01*
X202899Y597663D01*
X204185D01*
X205035Y598513D01*
X205992D01*
X206692Y599213D01*
G01X192960Y628510D02*
X191500Y629970D01*
Y635083D01*
X187600Y638983D01*
Y644300D01*
X183150Y648750D01*
Y703650D01*
X185100Y705600D01*
G01X187900Y628500D02*
Y635300D01*
X183117Y640083D01*
Y640983D01*
X179050Y645050D01*
Y704550D01*
X183800Y709300D01*
X184800D01*
G01X268900Y445150D02*
X261500Y452550D01*
Y473700D01*
X261700Y473900D01*
Y500187D01*
X258381Y503506D01*
Y509498D01*
G01X244700Y451200D02*
Y453300D01*
X247790Y456390D01*
Y495847D01*
X248299Y496356D01*
Y510699D01*
X248298Y510700D01*
Y512356D01*
X249266Y513324D01*
Y519976D01*
X251100Y521810D01*
Y527717D01*
X249000Y529817D01*
Y537240D01*
X247251Y538989D01*
X247249D01*
X242399Y543841D01*
X241893Y544347D01*
Y552239D01*
X244761Y555107D01*
Y557200D01*
X247335Y559774D01*
Y573564D01*
X252400Y578629D01*
Y580200D01*
X254400Y582200D01*
X260120D01*
X261308Y583388D01*
G01X236100Y445100D02*
Y455600D01*
X238700Y458200D01*
Y472700D01*
X241790Y475790D01*
Y496793D01*
X240900Y497683D01*
Y512800D01*
X238650Y515050D01*
Y535692D01*
X235893Y538449D01*
Y554726D01*
X238761Y557594D01*
Y588339D01*
X237100Y590000D01*
G01X239300Y443800D02*
Y453800D01*
X243790Y458290D01*
Y459403D01*
X243290Y459903D01*
X241200D01*
X240700Y460403D01*
Y461403D01*
X241200Y461903D01*
X243290D01*
X243790Y462403D01*
Y463403D01*
X243290Y463903D01*
X241200D01*
X240700Y464403D01*
Y465403D01*
X241200Y465903D01*
X243290D01*
X243790Y466403D01*
Y467403D01*
X243290Y467903D01*
X241200D01*
X240700Y468403D01*
Y469403D01*
X241200Y469903D01*
X243290D01*
X243790Y470403D01*
Y497505D01*
X244298Y498013D01*
Y512373D01*
X240650Y516021D01*
Y536521D01*
X237893Y539278D01*
Y553897D01*
X240761Y556765D01*
Y579761D01*
X250700Y589700D01*
Y594756D01*
X248872Y596584D01*
Y602528D01*
X238360Y613040D01*
X232220D01*
X232130Y612950D01*
G01X243000Y443800D02*
X242200Y444600D01*
Y453800D01*
X245790Y457390D01*
Y496676D01*
X246298Y497184D01*
Y513202D01*
X244150Y515350D01*
Y518550D01*
X247000Y521400D01*
Y533000D01*
X239893Y540107D01*
Y553068D01*
X242761Y555936D01*
Y560344D01*
X243261Y560844D01*
X244800D01*
X245300Y561344D01*
Y562344D01*
X244800Y562844D01*
X243261D01*
X242761Y563344D01*
Y564344D01*
X243261Y564844D01*
X244800D01*
X245300Y565344D01*
Y566344D01*
X244800Y566844D01*
X243261D01*
X242761Y567344D01*
Y568344D01*
X243261Y568844D01*
X244800D01*
X245300Y569344D01*
Y570344D01*
X244800Y570844D01*
X243261D01*
X242761Y571344D01*
Y572749D01*
X243261Y573249D01*
X244700D01*
X245200Y573749D01*
Y574749D01*
X244700Y575249D01*
X243261D01*
X242761Y575749D01*
Y576861D01*
X243600Y577700D01*
X247600D01*
X249050Y579150D01*
Y582050D01*
X251650Y584650D01*
X255950D01*
X257700Y586400D01*
G01X247900Y445300D02*
Y453100D01*
X251490Y456690D01*
Y496110D01*
X250650Y496950D01*
Y511879D01*
X251266Y512495D01*
Y519147D01*
X253100Y520981D01*
Y529342D01*
X251000Y531442D01*
Y538070D01*
X243893Y545177D01*
Y551410D01*
X247596Y555113D01*
Y557206D01*
X249335Y558945D01*
Y566652D01*
X257333Y574650D01*
X258367D01*
X260117Y576400D01*
X261500D01*
G01X260600Y442600D02*
Y449683D01*
X256800Y453483D01*
Y455000D01*
X256350Y455450D01*
Y510367D01*
X255963Y510754D01*
Y518186D01*
X257100Y519323D01*
Y532150D01*
X255150Y534100D01*
Y552750D01*
X253055Y554845D01*
Y556528D01*
X254138Y557611D01*
X254333D01*
X260950Y564228D01*
Y568500D01*
X259250Y570200D01*
Y572367D01*
X260583Y573700D01*
X261417D01*
X263850Y576133D01*
Y593850D01*
X256126Y601574D01*
Y605374D01*
X251900Y609600D01*
G01X250500Y451300D02*
Y452600D01*
X253490Y455590D01*
Y497210D01*
X252650Y498050D01*
Y511050D01*
X253266Y511666D01*
Y518318D01*
X255100Y520152D01*
Y530171D01*
X253000Y532271D01*
Y544217D01*
X249596Y547621D01*
Y555898D01*
X257484Y563786D01*
X257891D01*
G01X232200Y445600D02*
Y455950D01*
X235550Y459300D01*
Y478851D01*
X236550Y479851D01*
Y506851D01*
X235150Y508251D01*
Y525599D01*
X232400Y528349D01*
Y533200D01*
G01X275300Y668749D02*
X276300Y667749D01*
Y663350D01*
X261900Y648950D01*
Y598629D01*
X266100Y594429D01*
Y574000D01*
X264400Y572300D01*
X263050Y570949D01*
Y557672D01*
X261366Y555988D01*
Y554689D01*
X258891Y552214D01*
Y538726D01*
X259450Y538167D01*
Y532629D01*
X260700Y531379D01*
Y525900D01*
X261200Y525400D01*
G01X258100Y516400D02*
Y517420D01*
X263100Y522420D01*
Y527542D01*
X262483Y528159D01*
Y531718D01*
X260950Y533251D01*
Y542491D01*
X260741Y542700D01*
G01X228800Y542100D02*
X226300Y539600D01*
Y523437D01*
X225914Y523051D01*
G01X231800Y512100D02*
X230450Y513450D01*
Y545484D01*
X228313Y547621D01*
Y552169D01*
G01X212992Y548819D02*
X214542Y547269D01*
Y536158D01*
X223600Y527100D01*
Y512400D01*
G01X277603Y479948D02*
Y494068D01*
X274469Y497202D01*
Y534707D01*
X275400Y535638D01*
Y541007D01*
X278380Y543987D01*
Y560508D01*
X282715Y564843D01*
Y571819D01*
X284000Y573104D01*
Y602373D01*
X288184Y606557D01*
Y606558D01*
X291630Y610004D01*
Y622154D01*
X283700Y630084D01*
Y634781D01*
X284900Y635981D01*
Y676800D01*
X276800Y684900D01*
Y697925D01*
G01X282000Y583500D02*
Y573933D01*
X280715Y572648D01*
Y565672D01*
X276379Y561336D01*
Y545147D01*
X273400Y542168D01*
Y536467D01*
X272469Y535536D01*
Y487935D01*
X274800Y485604D01*
Y479200D01*
X277600Y476400D01*
Y470300D01*
X281200Y466700D01*
Y462200D01*
X280100Y461100D01*
Y454700D01*
X281200Y453600D01*
Y453500D01*
G01X233607Y557671D02*
X231039Y555103D01*
Y548842D01*
X233892Y545989D01*
Y537621D01*
X236650Y534863D01*
Y513050D01*
X238400Y511300D01*
G01X267800Y479900D02*
Y480999D01*
X264002Y484797D01*
Y507335D01*
X265274Y508607D01*
Y509512D01*
G01X212992Y561417D02*
X214594Y563019D01*
X216788D01*
X227415Y573646D01*
Y594608D01*
X233200Y600393D01*
X240438D01*
X243322Y597509D01*
G01X234205Y598743D02*
X233643D01*
X231495Y596595D01*
Y589768D01*
X228315Y586588D01*
Y564779D01*
X217106Y553570D01*
X214593D01*
X212992Y551969D01*
G01X233258Y595693D02*
Y590258D01*
X229215Y586215D01*
Y562542D01*
X218643Y551970D01*
X216141D01*
G01X267957Y537304D02*
X268841Y538188D01*
Y544715D01*
X272266Y548140D01*
Y563448D01*
X275132Y566314D01*
Y566415D01*
X275350Y566633D01*
Y577887D01*
X274839Y578398D01*
Y578680D01*
X274623Y578896D01*
G01X271357Y537253D02*
Y543870D01*
X274266Y546779D01*
Y562052D01*
X277350Y565136D01*
Y578716D01*
X276839Y579227D01*
Y582309D01*
G01X277048Y590470D02*
X278898Y592320D01*
Y599393D01*
X286685Y607180D01*
Y607181D01*
X288947Y609443D01*
Y622641D01*
X281718Y629870D01*
X273714D01*
G01X239400Y677900D02*
X244750Y683250D01*
X256976D01*
X266300Y692574D01*
G01X325300Y648700D02*
X325100Y648500D01*
X323986D01*
X319350Y643864D01*
Y629948D01*
X314250Y624848D01*
Y592090D01*
X309350Y587190D01*
Y579775D01*
X308350Y578775D01*
Y556710D01*
X307752Y556112D01*
Y544075D01*
X305653Y541976D01*
Y528633D01*
X306185Y528101D01*
Y517700D01*
X306700Y517185D01*
Y509800D01*
X304307Y507407D01*
Y501329D01*
X289764Y486786D01*
Y462244D01*
X310308Y441700D01*
X325378D01*
X329400Y437678D01*
Y431138D01*
X337249Y423289D01*
Y403700D01*
X326232Y392683D01*
Y271500D01*
X325132Y270400D01*
Y181800D01*
X327900Y179032D01*
Y171849D01*
X333050Y166699D01*
Y145652D01*
X310353Y122955D01*
Y62159D01*
G01X540179Y111036D02*
X526200Y97057D01*
X515501D01*
X499944Y81500D01*
X488261D01*
X480216Y73455D01*
X474050D01*
X467945Y67350D01*
X432000D01*
X428150Y63500D01*
Y30070D01*
X415330Y17250D01*
X333278D01*
X328578Y21950D01*
X324659D01*
X312970Y33639D01*
Y123450D01*
X334550Y145030D01*
Y167321D01*
X329500Y172371D01*
Y180100D01*
X326632Y182968D01*
Y268432D01*
X330763Y272563D01*
Y380237D01*
X330500Y380500D01*
Y394351D01*
X338749Y402600D01*
Y423911D01*
X330900Y431760D01*
Y438300D01*
X325600Y443600D01*
X310530D01*
X291264Y462866D01*
Y483813D01*
X310542Y503091D01*
Y510434D01*
X312253Y512145D01*
Y554248D01*
X312850Y554845D01*
Y576911D01*
X313852Y577913D01*
Y583329D01*
X322323Y591800D01*
Y624435D01*
X328150Y630262D01*
Y642050D01*
X330400Y644300D01*
G01X539346Y114333D02*
X523570Y98557D01*
X513565D01*
X498053Y83045D01*
X487684D01*
X479594Y74955D01*
X473133D01*
X467050Y68872D01*
X429228D01*
X425957Y65601D01*
X402456D01*
X386187Y49332D01*
Y41909D01*
X370825Y26547D01*
X324306D01*
X315970Y34883D01*
Y122206D01*
X338063Y144299D01*
Y168052D01*
X332957Y173158D01*
Y181475D01*
X329632Y184800D01*
Y262232D01*
X339247Y271847D01*
Y286489D01*
X339658Y286900D01*
Y341773D01*
X332600Y348831D01*
Y381100D01*
X332100Y381600D01*
Y393351D01*
X340249Y401500D01*
Y424533D01*
X332400Y432382D01*
Y439056D01*
X326356Y445100D01*
X311381D01*
X301612Y454869D01*
X300919Y455333D01*
X297853Y458399D01*
X297389Y459092D01*
X292764Y463718D01*
Y483191D01*
X312043Y502470D01*
Y509813D01*
X313886Y511656D01*
Y553759D01*
X314350Y554223D01*
Y576289D01*
X320193Y582132D01*
Y587548D01*
X323823Y591178D01*
Y623813D01*
X332650Y632640D01*
Y642450D01*
X334700Y644500D01*
G01X520866Y173229D02*
X523116Y170979D01*
Y122151D01*
X513266Y112301D01*
X508529D01*
X508528Y112300D01*
X508527D01*
X494548Y98321D01*
Y98320D01*
X493510Y97282D01*
X483479D01*
X474152Y87955D01*
X467743D01*
X462122Y82334D01*
X400598D01*
X383931Y65667D01*
X381810D01*
X381809Y65668D01*
X380153D01*
X370753Y56268D01*
Y48105D01*
X368900Y46252D01*
Y43688D01*
X364872Y39660D01*
X334310D01*
X328970Y45000D01*
Y116161D01*
X354395Y141586D01*
Y170734D01*
X350922Y174207D01*
Y195931D01*
X348353Y198500D01*
Y245297D01*
X354808Y251752D01*
Y434796D01*
X340200Y449404D01*
Y484647D01*
X334699Y490148D01*
Y490952D01*
X334700D01*
Y499795D01*
X334699Y499796D01*
Y502025D01*
X326200Y510524D01*
Y512429D01*
X327022Y513251D01*
Y520371D01*
X324780Y522613D01*
Y534128D01*
X323455Y535453D01*
Y557106D01*
X323659Y557310D01*
G01X520866Y178740D02*
X525116Y174490D01*
Y121322D01*
X514095Y110301D01*
X509358D01*
X509357Y110300D01*
X509356D01*
X496548Y97492D01*
Y97491D01*
X494338Y95281D01*
X484307D01*
X474981Y85955D01*
X468572D01*
X462951Y80334D01*
X401427D01*
X384760Y63667D01*
X380981D01*
X372753Y55439D01*
Y44712D01*
X365701Y37660D01*
X339239D01*
X339238Y37659D01*
X333482D01*
X326970Y44171D01*
Y116990D01*
X352395Y142415D01*
Y169905D01*
X346232Y176068D01*
Y246005D01*
X352808Y252581D01*
Y433967D01*
X338200Y448575D01*
Y483818D01*
X332699Y489319D01*
Y501196D01*
X323137Y510758D01*
Y521330D01*
X320736Y523731D01*
Y539356D01*
X321455Y540075D01*
Y562555D01*
X324200Y565300D01*
G01X346500Y435200D02*
X350808Y430892D01*
Y253410D01*
X344232Y246834D01*
Y175239D01*
X350395Y169076D01*
Y143244D01*
X324970Y117819D01*
Y43342D01*
X332653Y35659D01*
X340067D01*
X340068Y35660D01*
X366530D01*
X374753Y43883D01*
Y54610D01*
X380729Y60586D01*
X381971D01*
X381972Y60585D01*
X384507D01*
X402256Y78334D01*
X463780D01*
X469401Y83955D01*
X475810D01*
X485136Y93281D01*
X495167D01*
X498548Y96662D01*
Y96663D01*
X510185Y108300D01*
X517781D01*
X530203Y120722D01*
Y157593D01*
X527953Y159843D01*
G01X335100Y650600D02*
Y647100D01*
X336900Y645300D01*
Y641583D01*
X337450Y641033D01*
Y639250D01*
X339950Y636750D01*
Y635033D01*
X337149Y632232D01*
Y627449D01*
X326900Y617200D01*
Y590011D01*
X323194Y586305D01*
Y580800D01*
X317350Y574956D01*
Y552979D01*
X316886Y552515D01*
Y509626D01*
X317900Y508612D01*
Y503700D01*
X295764Y481564D01*
Y464962D01*
X299719Y461006D01*
X300183Y460313D01*
X302833Y457663D01*
X303526Y457199D01*
X312225Y448500D01*
X327200D01*
X335400Y440300D01*
Y433626D01*
X343249Y425777D01*
Y400000D01*
X339432Y396183D01*
Y357716D01*
X344808Y352340D01*
Y262108D01*
X332632Y249932D01*
Y186600D01*
X336179Y183053D01*
Y174180D01*
X341063Y169296D01*
Y145543D01*
X341064Y145542D01*
Y143056D01*
X318970Y120962D01*
Y36127D01*
X325550Y29547D01*
X369581D01*
X383187Y43153D01*
Y50577D01*
X401211Y68601D01*
X424395D01*
X427666Y71872D01*
X465806D01*
X471889Y77955D01*
X478298D01*
X487624Y87281D01*
X497655D01*
X512368Y101994D01*
X519205D01*
X521198Y101996D01*
X538606Y119404D01*
X543058D01*
X544376Y120722D01*
Y152081D01*
X542126Y154331D01*
G01X338100Y635800D02*
X337200D01*
X334500Y633100D01*
Y632199D01*
X325324Y623023D01*
Y590557D01*
X321693Y586926D01*
Y581510D01*
X315850Y575667D01*
Y553601D01*
X315386Y553137D01*
Y509004D01*
X316250Y508140D01*
Y504411D01*
X294264Y482425D01*
Y464340D01*
X298554Y460049D01*
X299018Y459356D01*
X301876Y456498D01*
X302569Y456034D01*
X312003Y446600D01*
X326978D01*
X333900Y439678D01*
Y433004D01*
X341749Y425155D01*
Y400700D01*
X337932Y396883D01*
Y356820D01*
X341158Y353594D01*
Y286200D01*
X340747Y285789D01*
Y271147D01*
X331132Y261532D01*
Y185668D01*
X334618Y182182D01*
Y173619D01*
X339563Y168674D01*
Y144921D01*
X339564Y144920D01*
Y143678D01*
X317470Y121584D01*
Y35505D01*
X324928Y28047D01*
X370203D01*
X384687Y42531D01*
Y49955D01*
X401833Y67101D01*
X425335D01*
X428606Y70372D01*
X466428D01*
X472511Y76455D01*
X478920D01*
X488246Y85781D01*
X498277D01*
X512597Y100101D01*
X521425D01*
X539228Y117904D01*
X543680D01*
X545876Y120100D01*
Y156093D01*
X542126Y159843D01*
G01X325400Y505800D02*
Y493789D01*
X335200Y483989D01*
Y483988D01*
X335886Y483302D01*
Y464340D01*
X331600Y460053D01*
Y449600D01*
X340650Y440550D01*
Y432620D01*
X346249Y427021D01*
Y398049D01*
X342732Y394532D01*
Y358660D01*
X347808Y353584D01*
Y260300D01*
X340032Y252524D01*
Y175195D01*
X347395Y167832D01*
Y145143D01*
X321970Y119718D01*
Y42098D01*
X331521Y32547D01*
X367661D01*
X377753Y42639D01*
Y53366D01*
X381972Y57585D01*
X385751D01*
X403500Y75334D01*
X465024D01*
X470645Y80955D01*
X477054D01*
X486380Y90281D01*
X496411D01*
X511430Y105300D01*
X519025D01*
X537289Y123564D01*
Y156805D01*
X535039Y159055D01*
G01Y164567D02*
X538789Y160817D01*
Y122942D01*
X519647Y103800D01*
X512052D01*
X497033Y88781D01*
X487002D01*
X477676Y79455D01*
X471267D01*
X465646Y73834D01*
X404322D01*
X382400Y51912D01*
X380912D01*
X379253Y50253D01*
Y42017D01*
X368283Y31047D01*
X326172D01*
X320470Y36749D01*
Y120340D01*
X345895Y145765D01*
Y167210D01*
X338532Y174573D01*
Y253424D01*
X346308Y261200D01*
Y352962D01*
X340932Y358338D01*
Y395083D01*
X344749Y398900D01*
Y426399D01*
X336900Y434248D01*
Y441300D01*
X330000Y448200D01*
Y460575D01*
X334386Y464962D01*
Y482680D01*
X319850Y497216D01*
Y508784D01*
X318736Y509898D01*
Y549697D01*
G01X535039Y178740D02*
X531703Y175404D01*
Y120100D01*
X518403Y106800D01*
X510808D01*
X495789Y91781D01*
X485758D01*
X476432Y82455D01*
X470023D01*
X464402Y76834D01*
X402878D01*
X385129Y59085D01*
X381350D01*
X376253Y53988D01*
Y43261D01*
X367152Y34160D01*
X340690D01*
X340689Y34159D01*
X332031D01*
X323470Y42720D01*
Y119096D01*
X348895Y144521D01*
Y168454D01*
X342112Y175237D01*
Y247912D01*
X345121Y250921D01*
Y255421D01*
X349308Y259608D01*
Y429292D01*
X344650Y433950D01*
Y439296D01*
X333850Y450096D01*
Y458400D01*
G01X354798Y22452D02*
X352203Y25047D01*
X323684D01*
X314470Y34261D01*
Y122828D01*
X336563Y144921D01*
Y167430D01*
X331200Y172793D01*
Y180800D01*
X328132Y183868D01*
Y263032D01*
X337746Y272646D01*
Y288647D01*
X337808Y288709D01*
G01X278400Y463300D02*
X278000Y462900D01*
Y453400D01*
X280665Y450735D01*
X292236D01*
X309871Y433100D01*
X323916D01*
X335749Y421267D01*
Y404949D01*
X324200Y393400D01*
X316900D01*
X314000Y390500D01*
G01X286700Y457500D02*
X288264Y459064D01*
Y492002D01*
X290863Y494601D01*
Y508163D01*
X300185Y517485D01*
Y524522D01*
X298514Y526193D01*
Y550184D01*
G01X323759Y435145D02*
X321904Y437000D01*
X308800D01*
X292600Y453200D01*
X284971D01*
X282699Y455472D01*
Y457128D01*
X282700Y457129D01*
Y460500D01*
X284264Y462064D01*
Y493660D01*
X286862Y496258D01*
Y510957D01*
X285298Y512521D01*
X285140D01*
X282047Y515614D01*
Y553082D01*
X283649Y554684D01*
Y554685D01*
X284670Y555706D01*
Y561847D01*
X286215Y563392D01*
Y570368D01*
X287510Y571663D01*
Y600932D01*
X291685Y605107D01*
Y605108D01*
X295130Y608553D01*
Y623605D01*
X287200Y631535D01*
Y632600D01*
G01X327159Y435201D02*
X323060Y439300D01*
X309892D01*
X309492Y439700D01*
X309479D01*
X293979Y455200D01*
X285800D01*
X284700Y456300D01*
Y459100D01*
X286264Y460664D01*
Y492831D01*
X288862Y495429D01*
Y511786D01*
X286127Y514521D01*
X285969D01*
X284047Y516443D01*
Y543241D01*
X288876Y548070D01*
Y563224D01*
X292850Y567198D01*
Y571577D01*
X289530Y574897D01*
Y600123D01*
X293685Y604278D01*
Y604279D01*
X297130Y607724D01*
Y624434D01*
X290900Y630664D01*
Y630900D01*
G01X278769Y700697D02*
Y689648D01*
X286400Y682017D01*
Y635359D01*
X285200Y634159D01*
Y630706D01*
X293130Y622776D01*
Y609382D01*
X289684Y605936D01*
Y605935D01*
X285510Y601761D01*
Y572492D01*
X284215Y571197D01*
Y564221D01*
X282670Y562676D01*
Y556557D01*
X279880Y553767D01*
Y539381D01*
X276900Y536401D01*
Y535016D01*
X275969Y534085D01*
Y508855D01*
X276634Y508190D01*
Y498311D01*
G01X302307Y505799D02*
Y513853D01*
X304185Y515731D01*
Y526180D01*
X302514Y527851D01*
Y541666D01*
X304665Y543817D01*
Y545901D01*
X305752Y546988D01*
Y556941D01*
X306350Y557539D01*
Y579604D01*
X307350Y580604D01*
Y588140D01*
X310100Y590890D01*
Y594917D01*
X312250Y597067D01*
Y625677D01*
X317350Y630777D01*
Y647800D01*
X315300Y649850D01*
Y654750D01*
X310821Y659229D01*
Y666987D01*
X309000Y668808D01*
Y686521D01*
X316679Y694200D01*
X327600D01*
X329250Y695850D01*
Y699500D01*
X327250Y701500D01*
G01X298907Y505851D02*
X297000Y507758D01*
Y511471D01*
X302185Y516656D01*
Y525351D01*
X300514Y527022D01*
Y542495D01*
X302326Y544307D01*
Y548343D01*
X301670Y548999D01*
Y551455D01*
X303752Y553537D01*
Y557770D01*
X304350Y558368D01*
Y580433D01*
X305350Y581433D01*
Y593304D01*
X310250Y598204D01*
Y605582D01*
X310249Y605583D01*
Y607239D01*
X310250Y607240D01*
Y626506D01*
X315337Y631593D01*
Y646763D01*
X310600Y651500D01*
Y655750D01*
X308821Y657529D01*
Y666158D01*
X307000Y667979D01*
Y687350D01*
X316426Y696776D01*
X327162D01*
G01X294500Y630600D02*
X299630Y625470D01*
Y606687D01*
X297649Y604706D01*
X297648D01*
X296185Y603243D01*
Y603242D01*
X294985Y602042D01*
Y583985D01*
X293700Y582700D01*
Y574263D01*
X295350Y572613D01*
Y566162D01*
X291376Y562188D01*
Y546540D01*
X288045Y543209D01*
Y520055D01*
X292100Y516000D01*
G01X297400Y517981D02*
X294046D01*
X290545Y521482D01*
Y542173D01*
X293876Y545504D01*
Y554259D01*
X299850Y560233D01*
Y578577D01*
X298750Y579677D01*
Y602271D01*
X302130Y605651D01*
Y626620D01*
X298100Y630650D01*
G01X280100Y532100D02*
X279969Y531969D01*
Y513900D01*
X284789Y509080D01*
Y497014D01*
X281973Y494198D01*
Y474930D01*
X282403Y474500D01*
G01X279664Y535473D02*
Y535164D01*
X278900Y534400D01*
Y534187D01*
X277969Y533256D01*
Y513071D01*
X282789Y508251D01*
Y497843D01*
X279972Y495026D01*
Y472628D01*
X282400Y470200D01*
G01X337346Y545100D02*
Y544968D01*
X331315Y538937D01*
Y518757D01*
X329350Y516792D01*
Y512550D01*
X328400Y511600D01*
X328200D01*
G01X331200Y508900D02*
Y509100D01*
X330850Y509450D01*
Y516105D01*
X332815Y518070D01*
Y523496D01*
X335774Y526455D01*
Y533778D01*
X335700Y533852D01*
Y540039D01*
X338411Y542750D01*
X338947D01*
X341197Y545000D01*
X341316D01*
G01X341493Y541250D02*
X339799Y539556D01*
Y532821D01*
X337275Y530297D01*
Y525834D01*
X334689Y523248D01*
Y508939D01*
X334650Y508900D01*
G01X333512Y553888D02*
X332579Y554821D01*
Y563274D01*
X332030Y563823D01*
Y582830D01*
X334900Y585700D01*
Y586100D01*
G01X336367Y549943D02*
X335855Y550455D01*
Y562827D01*
X334030Y564652D01*
Y579730D01*
X337300Y583000D01*
G01X293087Y530571D02*
Y541179D01*
X296376Y544468D01*
Y551145D01*
X300257Y555026D01*
Y557103D01*
X301752Y558598D01*
Y558599D01*
X302350Y559197D01*
Y579613D01*
X301250Y580713D01*
Y592033D01*
X308250Y599033D01*
Y604753D01*
X308249Y604754D01*
Y608068D01*
X308250Y608069D01*
Y627335D01*
X313336Y632421D01*
Y645421D01*
X305936Y652821D01*
Y654687D01*
X306821Y655572D01*
Y665329D01*
X304700Y667450D01*
Y668500D01*
G01X513779Y154331D02*
X511529Y152081D01*
Y124496D01*
X492826Y105793D01*
X476386D01*
X459427Y88834D01*
X436586D01*
X434081Y91339D01*
X407485D01*
X405097Y93727D01*
Y93728D01*
X378227Y120598D01*
Y164716D01*
X376677Y166266D01*
Y207323D01*
X372591Y211409D01*
Y371734D01*
X365658Y378667D01*
Y449342D01*
X362100Y452900D01*
Y455200D01*
X359117Y458183D01*
Y471017D01*
X360960Y472860D01*
Y479198D01*
X359748Y480410D01*
Y500168D01*
X361300Y501720D01*
Y503617D01*
X359950Y504967D01*
Y544061D01*
X358119Y545892D01*
Y552032D01*
X356790Y553361D01*
Y565892D01*
X354097Y568585D01*
Y572964D01*
X346464Y580597D01*
Y587352D01*
X349850Y590738D01*
Y628431D01*
X342450Y635831D01*
Y637786D01*
X339950Y640286D01*
Y642069D01*
X339400Y642619D01*
Y649836D01*
X333404Y655832D01*
X331718D01*
G01X317689Y599833D02*
X315750Y601772D01*
Y624226D01*
X320850Y629326D01*
Y643242D01*
X323269Y645661D01*
X325061D01*
X327603Y648203D01*
Y649403D01*
X328900Y650700D01*
X329100D01*
G01X513779Y159843D02*
X509029Y155093D01*
Y125532D01*
X491790Y108293D01*
X475350D01*
X460896Y93839D01*
X408522D01*
X380727Y121634D01*
Y165752D01*
X379177Y167302D01*
Y208374D01*
X375091Y212460D01*
Y372770D01*
X368158Y379703D01*
Y455042D01*
X361617Y461583D01*
Y469981D01*
X363461Y471825D01*
Y473895D01*
X363460Y473896D01*
Y480234D01*
X362248Y481446D01*
Y499131D01*
X363800Y500683D01*
Y504653D01*
X362450Y506003D01*
Y545097D01*
X360619Y546928D01*
Y553068D01*
X359290Y554397D01*
Y566928D01*
X356929Y569289D01*
Y591662D01*
X361108Y595841D01*
Y626367D01*
X348950Y638525D01*
Y640480D01*
X346450Y642980D01*
Y644763D01*
X345900Y645313D01*
Y654800D01*
X340084Y660616D01*
Y664964D01*
X336448Y668600D01*
X318833D01*
X317750Y669683D01*
Y670100D01*
X316000Y671850D01*
G01X339804Y679030D02*
X349900Y668934D01*
Y657872D01*
X350900Y656872D01*
Y650000D01*
X353175Y647725D01*
Y643327D01*
X358502Y638000D01*
X359680D01*
X367226Y630454D01*
Y625632D01*
X373350Y619508D01*
Y605592D01*
X371650Y603892D01*
Y593497D01*
X367122Y588969D01*
Y585633D01*
X366750Y585261D01*
Y570076D01*
X366790Y570036D01*
Y565500D01*
X368176Y564114D01*
Y559155D01*
X372122Y555209D01*
Y542325D01*
X370950Y541153D01*
Y524543D01*
X367150Y520743D01*
Y507668D01*
X369650Y505168D01*
Y496380D01*
X366748Y493478D01*
Y483311D01*
X367968Y482091D01*
Y474832D01*
X368800Y474000D01*
Y463100D01*
X372100Y459800D01*
Y456200D01*
X374838Y453462D01*
Y377284D01*
X377591Y374531D01*
Y213496D01*
X381677Y209410D01*
Y168338D01*
X383227Y166788D01*
Y122670D01*
X409558Y96339D01*
X459860D01*
X471423Y107902D01*
Y110117D01*
X475510Y114204D01*
Y155593D01*
X471260Y159843D01*
G01X289700Y678830D02*
X289100Y679430D01*
Y693340D01*
X285070Y697370D01*
Y713116D01*
X280646Y717540D01*
G01X381269Y94981D02*
Y104961D01*
X368125Y118105D01*
Y165313D01*
X370149Y167337D01*
G01X384666Y93741D02*
X383269Y95138D01*
Y105790D01*
X370125Y118934D01*
Y162931D01*
X370882Y163688D01*
G01X457086Y154331D02*
X454751Y151996D01*
Y121115D01*
X443540Y109904D01*
X417262D01*
X405141Y122025D01*
Y149765D01*
X402066Y152840D01*
X399487D01*
X398355Y153972D01*
Y168513D01*
X392102Y174766D01*
Y175384D01*
G01X392458Y171676D02*
Y170874D01*
X395540Y167792D01*
Y153251D01*
X398451Y150340D01*
X401030D01*
X402640Y148730D01*
Y120990D01*
X416226Y107404D01*
X446018D01*
X459336Y120722D01*
Y166254D01*
X457086Y168504D01*
G01X344163Y553395D02*
X346101Y551457D01*
Y549198D01*
X347619Y547680D01*
Y524111D01*
X347049Y523541D01*
Y504400D01*
X345737Y503088D01*
X343476D01*
X342500Y502112D01*
Y491367D01*
X346550Y487317D01*
Y452035D01*
X361158Y437427D01*
Y245558D01*
X355942Y240342D01*
Y200029D01*
X357272Y198699D01*
Y177435D01*
X364125Y170582D01*
Y112049D01*
X375285Y100889D01*
Y94683D01*
X387827Y82141D01*
X395693D01*
X397886Y84334D01*
X461293D01*
X466914Y89955D01*
X473323D01*
X482650Y99282D01*
X492680D01*
X507698Y114300D01*
X507699D01*
X507700Y114301D01*
X512437D01*
X518280Y120144D01*
Y156469D01*
X520866Y159055D01*
G01Y164567D02*
X516269Y159970D01*
Y120962D01*
X511608Y116301D01*
X506870D01*
X491851Y101282D01*
X481821D01*
X472494Y91955D01*
X466085D01*
X460464Y86334D01*
X397057D01*
X394864Y84141D01*
X388656D01*
X377285Y95512D01*
Y101718D01*
X366125Y112878D01*
Y172539D01*
X359272Y179392D01*
Y199528D01*
X357942Y200858D01*
Y236242D01*
X363642Y241942D01*
Y243921D01*
X363158Y244405D01*
Y438256D01*
X348550Y452864D01*
Y488146D01*
X346900Y489796D01*
Y501422D01*
X349049Y503571D01*
Y522712D01*
X349619Y523282D01*
Y548509D01*
X348101Y550027D01*
Y554724D01*
X345259Y557566D01*
G01X464173Y173229D02*
X466423Y170979D01*
Y109975D01*
X457787Y101339D01*
X411631D01*
X391791Y121179D01*
Y165708D01*
X386677Y170822D01*
Y327596D01*
X385313Y328960D01*
Y441279D01*
X379876Y446716D01*
Y462530D01*
X378000Y464406D01*
Y475325D01*
X377229Y476096D01*
Y490035D01*
X376215Y491049D01*
Y496670D01*
X378729Y499184D01*
Y512374D01*
X381986Y515631D01*
G01X374751Y485636D02*
X375729Y484658D01*
Y475474D01*
X376500Y474703D01*
Y463784D01*
X378376Y461908D01*
Y382408D01*
X381091Y379693D01*
Y217837D01*
X385177Y213751D01*
Y170200D01*
X390291Y165086D01*
Y120557D01*
X411009Y99839D01*
X458409D01*
X467923Y109353D01*
Y174990D01*
X464173Y178740D01*
G01X471260Y154331D02*
X473510Y152081D01*
Y115033D01*
X469423Y110946D01*
Y108731D01*
X459031Y98339D01*
X410387D01*
X385227Y123499D01*
Y167722D01*
X383677Y169272D01*
Y210939D01*
X379591Y215025D01*
Y377076D01*
X378492Y378175D01*
G01X457086Y174016D02*
X461587Y169515D01*
Y118384D01*
X463886Y116085D01*
Y110136D01*
X456589Y102839D01*
X412253D01*
X393291Y121801D01*
Y166330D01*
X388177Y171444D01*
Y328218D01*
X386813Y329582D01*
Y442147D01*
X381376Y447584D01*
Y463152D01*
X379500Y465028D01*
Y475947D01*
X378729Y476718D01*
Y495638D01*
X378267Y496100D01*
G01X367358Y372531D02*
X369321Y370568D01*
Y176997D01*
X374177Y172141D01*
Y165230D01*
X375727Y163680D01*
Y119562D01*
X388274Y107015D01*
Y97526D01*
X390964Y94836D01*
Y87226D01*
G01X367471Y369120D02*
X367468Y369117D01*
Y176728D01*
X372677Y171519D01*
Y164608D01*
X374227Y163058D01*
Y118940D01*
X386774Y106393D01*
Y96904D01*
X389464Y94214D01*
Y92764D01*
X388700Y92000D01*
Y89800D01*
G01X442913Y159843D02*
X440178Y157108D01*
Y125425D01*
X432657Y117904D01*
X420579D01*
X413200Y125283D01*
Y161448D01*
X392677Y181971D01*
Y330788D01*
X391313Y332152D01*
Y442593D01*
X394431Y445711D01*
Y485523D01*
X392229Y487725D01*
Y504264D01*
X393729Y505764D01*
Y552439D01*
X392427Y553741D01*
Y563416D01*
X390547Y565296D01*
Y578091D01*
X394161Y581705D01*
Y611701D01*
X394517Y612057D01*
Y646366D01*
X392529Y648354D01*
Y657424D01*
X394499Y659394D01*
Y674818D01*
X393567Y675750D01*
X392033D01*
X390950Y676833D01*
Y682766D01*
X394499Y686315D01*
Y690963D01*
X396166Y692630D01*
G01X404727Y162141D02*
X407700Y159168D01*
Y123002D01*
X418298Y112404D01*
X442504D01*
X443967Y113867D01*
Y113868D01*
X452250Y122151D01*
Y155007D01*
X457086Y159843D01*
G01X400080Y519500D02*
Y503627D01*
X398229Y501776D01*
Y490213D01*
X400431Y488011D01*
Y184827D01*
X412029Y173229D01*
X421653D01*
G01X400093Y536351D02*
X401931Y534513D01*
Y185449D01*
X408527Y178853D01*
X421540D01*
X421653Y178740D01*
G01X428740Y174016D02*
X424612Y169888D01*
Y126155D01*
X422585Y124128D01*
X420721D01*
X417700Y127149D01*
Y163314D01*
X397177Y183837D01*
Y350802D01*
X396561Y351418D01*
G01X450000Y164567D02*
X445732Y160299D01*
Y121291D01*
X440845Y116404D01*
X419957D01*
X411700Y124661D01*
Y160826D01*
X391177Y181349D01*
Y329462D01*
X389813Y330826D01*
Y443215D01*
X392931Y446333D01*
Y484901D01*
X390729Y487103D01*
Y504886D01*
X392229Y506386D01*
Y551817D01*
X390927Y553119D01*
Y562794D01*
X389047Y564674D01*
Y579208D01*
X391993Y582154D01*
G01X421653Y164567D02*
X418569D01*
X398931Y184205D01*
Y487389D01*
X396729Y489591D01*
Y502398D01*
X398229Y503898D01*
Y537291D01*
X402017Y541079D01*
Y684400D01*
X399831Y686586D01*
X396419D01*
G01X450000Y159055D02*
X447232Y156287D01*
Y120669D01*
X441467Y114904D01*
X419335D01*
X410200Y124039D01*
Y160204D01*
X389677Y180727D01*
Y328840D01*
X388313Y330204D01*
Y444257D01*
X391431Y447375D01*
Y484279D01*
X389229Y486481D01*
Y507189D01*
X390229Y508189D01*
G01X428740Y154331D02*
X426113Y151704D01*
Y125534D01*
X423207Y122628D01*
X420099D01*
X416200Y126527D01*
Y162692D01*
X395677Y183215D01*
Y332032D01*
X394313Y333396D01*
Y441349D01*
X397431Y444467D01*
Y486767D01*
X395229Y488969D01*
Y503020D01*
X396729Y504520D01*
Y553683D01*
X395762Y554650D01*
Y564021D01*
X396017Y564276D01*
Y646988D01*
X394029Y648976D01*
Y656802D01*
X395999Y658772D01*
Y677299D01*
X394418Y678880D01*
Y681185D01*
X396419Y683186D01*
G01X442913Y174016D02*
X438319Y169422D01*
Y125688D01*
X432035Y119404D01*
X421201D01*
X414700Y125905D01*
Y162070D01*
X394177Y182593D01*
Y331410D01*
X392813Y332774D01*
Y441971D01*
X395931Y445089D01*
Y486145D01*
X393729Y488347D01*
Y503642D01*
X395229Y505142D01*
Y553061D01*
X393927Y554363D01*
Y564038D01*
X392047Y565918D01*
Y576840D01*
X393912Y578705D01*
G01X378492Y378175D02*
X376876Y379791D01*
Y460953D01*
X375000Y462829D01*
Y474081D01*
X374229Y474852D01*
Y482480D01*
X372630Y484079D01*
Y491985D01*
X374715Y494070D01*
Y498722D01*
G01X346303Y591947D02*
X343651Y589295D01*
Y577580D01*
X340380Y574309D01*
Y567283D01*
X343073Y564590D01*
X344300D01*
X350110Y558780D01*
Y550847D01*
X351619Y549338D01*
Y543198D01*
X353450Y541367D01*
Y537004D01*
X352030Y535584D01*
Y522864D01*
X351385Y522219D01*
Y488140D01*
X352500Y487025D01*
Y455818D01*
X350550Y453868D01*
Y453809D01*
X350491D01*
G01X387450Y454558D02*
Y454739D01*
X389431Y456720D01*
Y475917D01*
X385729Y479619D01*
Y509473D01*
X388729Y512473D01*
Y521619D01*
X384849Y525499D01*
G01X387396Y458126D02*
Y464204D01*
X384500Y467100D01*
Y478019D01*
X383729Y478790D01*
Y510302D01*
X386729Y513302D01*
Y519801D01*
X384849Y521681D01*
G01X367700Y685450D02*
X368450D01*
X370111Y687111D01*
X381154D01*
X384915Y683350D01*
Y646774D01*
X388017Y643672D01*
Y616932D01*
X386800Y615715D01*
Y611513D01*
X387661Y610652D01*
Y592154D01*
X387613Y592106D01*
Y590538D01*
X381150Y584075D01*
Y559619D01*
X381622Y559147D01*
Y547048D01*
X385900Y542770D01*
Y533541D01*
X384437Y532078D01*
X384436D01*
X382216Y529858D01*
Y518937D01*
X384000Y517153D01*
Y514109D01*
X381229Y511338D01*
Y477754D01*
X382000Y476983D01*
Y466064D01*
X383876Y464188D01*
Y449633D01*
X384395Y449114D01*
G01X343338Y679236D02*
X351900Y670674D01*
Y658701D01*
X352900Y657701D01*
Y650829D01*
X355175Y648554D01*
Y644156D01*
X358481Y640850D01*
X359659D01*
X369226Y631283D01*
Y626461D01*
X375350Y620337D01*
Y604763D01*
X373650Y603063D01*
Y592668D01*
X369122Y588140D01*
Y584804D01*
X368750Y584432D01*
Y570905D01*
X368790Y570865D01*
Y566329D01*
X370176Y564943D01*
Y559984D01*
X374122Y556038D01*
Y542767D01*
X375702Y541187D01*
Y535138D01*
X373616Y533052D01*
Y524100D01*
X371700Y522184D01*
Y495601D01*
X368748Y492649D01*
Y484140D01*
X369968Y482920D01*
Y475732D01*
X373000Y472700D01*
Y462000D01*
X374700Y460300D01*
G01X355400Y453800D02*
Y453700D01*
X354500Y454600D01*
Y487854D01*
X353450Y488904D01*
Y517130D01*
X355150Y518830D01*
Y535875D01*
X355450Y536175D01*
Y542196D01*
X353619Y544027D01*
Y550167D01*
X352289Y551497D01*
Y564028D01*
X348922Y567395D01*
Y569758D01*
X346590Y572090D01*
G01X357900Y450800D02*
Y455500D01*
X356500Y456900D01*
Y488683D01*
X355450Y489733D01*
Y500233D01*
X357250Y502033D01*
Y535146D01*
X357450Y535346D01*
Y543025D01*
X355619Y544856D01*
Y550996D01*
X354289Y552326D01*
Y562673D01*
X354290Y562674D01*
Y564856D01*
X351353Y567793D01*
Y571231D01*
X350278Y572306D01*
G01X363500Y464700D02*
X364817Y466017D01*
Y469645D01*
X365960Y470788D01*
Y471460D01*
X365968Y471468D01*
Y481262D01*
X364748Y482482D01*
Y494307D01*
X367650Y497209D01*
Y504339D01*
X365150Y506839D01*
Y522308D01*
X366581Y523739D01*
Y534338D01*
X364993Y535926D01*
Y555266D01*
X361790Y558469D01*
Y567964D01*
X359429Y570325D01*
Y590626D01*
X362799Y593996D01*
X364014D01*
G01X374715Y498722D02*
X377229Y501236D01*
Y512996D01*
X379716Y515483D01*
Y530894D01*
X383400Y534578D01*
Y541734D01*
X379122Y546012D01*
Y558110D01*
X378642Y558590D01*
Y586671D01*
X385161Y593190D01*
Y601356D01*
X385155Y601362D01*
Y601372D01*
X385161Y601378D01*
Y609614D01*
X384300Y610475D01*
Y619925D01*
G01X389288Y483500D02*
X387729Y485059D01*
Y508644D01*
X390729Y511644D01*
Y551195D01*
X389427Y552497D01*
Y562172D01*
X387547Y564052D01*
Y580272D01*
X388155Y580880D01*
Y584008D01*
X392661Y588514D01*
Y612323D01*
X393017Y612679D01*
Y645744D01*
X391029Y647732D01*
Y658046D01*
X392999Y660016D01*
Y673001D01*
X392500Y673500D01*
G01X373800Y503000D02*
X374729Y503929D01*
Y514032D01*
X377016Y516319D01*
Y532915D01*
X378202Y534101D01*
Y534102D01*
X380900Y536800D01*
Y540698D01*
X376622Y544976D01*
Y557074D01*
X376142Y557554D01*
Y588795D01*
X379850Y592503D01*
Y628396D01*
X374850Y633396D01*
Y639950D01*
X379595Y644695D01*
Y663960D01*
X378595Y664960D01*
G01X343200Y667600D02*
X347400Y663400D01*
Y656836D01*
X348400Y655836D01*
Y646900D01*
X350675Y644625D01*
Y642291D01*
X351450Y641516D01*
Y639561D01*
X358292Y632719D01*
X361425D01*
X364726Y629418D01*
Y624596D01*
X368983Y620339D01*
Y595300D01*
X367900Y594217D01*
X367772D01*
X362961Y589406D01*
Y582582D01*
X364250Y581293D01*
Y569040D01*
X364290Y569000D01*
Y559505D01*
X367493Y556302D01*
Y544907D01*
X369500Y542900D01*
G01X389999Y664697D02*
Y660552D01*
X389993Y660546D01*
X389992D01*
X388529Y659083D01*
Y646696D01*
X390517Y644708D01*
Y615895D01*
X389300Y614678D01*
Y612549D01*
X390161Y611688D01*
Y589550D01*
X384270Y583659D01*
Y580051D01*
X385047Y579274D01*
Y563016D01*
X386927Y561136D01*
Y551461D01*
X388641Y549747D01*
G01X399726Y562327D02*
X400017Y562618D01*
Y648646D01*
X398029Y650634D01*
Y654272D01*
X399999Y656242D01*
Y673422D01*
G01X399946Y558677D02*
X397762Y560861D01*
Y563192D01*
X398017Y563447D01*
Y647817D01*
X396029Y649805D01*
Y655101D01*
X397999Y657071D01*
Y678128D01*
X396419Y679708D01*
G01X372939Y559838D02*
X373109Y560008D01*
Y573081D01*
X370750Y575440D01*
Y583603D01*
X371122Y583975D01*
Y587311D01*
X375650Y591839D01*
Y602234D01*
X377350Y603934D01*
Y627360D01*
X372350Y632360D01*
Y640986D01*
X377095Y645731D01*
Y660775D01*
X373270Y664600D01*
Y678144D01*
X380387Y685261D01*
G01X384300Y619925D02*
Y621652D01*
X385517Y622869D01*
Y626400D01*
X377900Y634017D01*
Y639400D01*
X378450Y639950D01*
X379671D01*
X379676Y639955D01*
X381155D01*
X382308Y641108D01*
Y665022D01*
G01X346600Y714500D02*
Y709900D01*
X343815Y707115D01*
Y702054D01*
X346000Y699869D01*
Y684300D01*
G01X388626Y715509D02*
X389797Y714338D01*
Y695908D01*
X392500Y693205D01*
Y692500D01*
G01X545200Y69000D02*
X555501Y58699D01*
Y19837D01*
X551784Y16120D01*
X524950D01*
G01X481800Y71200D02*
Y72800D01*
X489000Y80000D01*
X500566D01*
X516123Y95557D01*
X527317D01*
X552061Y120301D01*
Y155605D01*
X556299Y159843D01*
G01X601311Y13521D02*
X603892Y10940D01*
X732540D01*
X739553Y17953D01*
Y85853D01*
X762949Y109249D01*
X763553D01*
X765751Y111447D01*
Y112051D01*
X778715Y125015D01*
X781615D01*
X873440Y216840D01*
Y317758D01*
X880750Y325068D01*
Y387402D01*
X899350Y406002D01*
Y459750D01*
X747200Y611900D01*
G01X638603Y296320D02*
X640503Y294420D01*
Y289204D01*
X638753Y287454D01*
X624614D01*
X624613Y287455D01*
X623371D01*
X623370Y287456D01*
X622128D01*
X615750Y281078D01*
Y221260D01*
X624000Y213010D01*
Y194955D01*
X602281Y173236D01*
Y87131D01*
X596300Y81150D01*
Y66950D01*
G01X642003Y296249D02*
Y288582D01*
X639375Y285954D01*
X623992D01*
X623991Y285955D01*
X622749D01*
X617250Y280456D01*
Y221882D01*
X625500Y213632D01*
Y194333D01*
X603781Y172614D01*
Y85731D01*
X599400Y81350D01*
Y66501D01*
X595900Y63001D01*
Y51590D01*
X604400Y43090D01*
Y19250D01*
X606650Y17000D01*
X661200D01*
X666400Y22200D01*
G01X645403Y296229D02*
Y289403D01*
X640454Y284454D01*
X623370D01*
X618750Y279834D01*
Y222504D01*
X627287Y213967D01*
Y193302D01*
X607252Y173267D01*
Y85503D01*
X602125Y80376D01*
Y63125D01*
X597950Y58950D01*
G01X593064Y400910D02*
X588442Y396288D01*
Y382232D01*
X586022Y379812D01*
Y346651D01*
X583101Y343730D01*
Y187897D01*
X574672Y179468D01*
Y104882D01*
X559900Y90110D01*
Y88400D01*
G01X593229Y397308D02*
X590808Y394887D01*
Y381339D01*
X588022Y378553D01*
Y345822D01*
X585101Y342901D01*
Y187068D01*
X576674Y178641D01*
Y103815D01*
X563064Y90205D01*
Y89076D01*
X563268Y88872D01*
G01X631069Y292512D02*
X627511Y288954D01*
X625236D01*
X625235Y288955D01*
X623993D01*
X623992Y288956D01*
X621506D01*
X614250Y281700D01*
Y220638D01*
X622500Y212388D01*
Y195577D01*
X599686Y172763D01*
Y103719D01*
X599682Y103715D01*
G01X586155Y393023D02*
Y383363D01*
X584022Y381230D01*
Y347480D01*
X581101Y344559D01*
Y188726D01*
X570975Y178600D01*
X562160D01*
G01X602075Y339970D02*
Y361417D01*
X603450Y362792D01*
Y387562D01*
X604848Y388960D01*
Y392848D01*
X605400Y393400D01*
G01X776500Y82700D02*
X766700Y72900D01*
Y52800D01*
X745672Y31772D01*
Y17706D01*
X735416Y7450D01*
X665900D01*
X665800Y7550D01*
G01X709079Y229564D02*
X710100Y228543D01*
Y226121D01*
X708579Y224600D01*
X702951D01*
X702101Y225450D01*
X686387D01*
X685887Y225950D01*
Y229050D01*
X685387Y229550D01*
X684387D01*
X683887Y229050D01*
Y225950D01*
X683387Y225450D01*
X682387D01*
X681887Y225950D01*
Y229050D01*
X681387Y229550D01*
X680387D01*
X679887Y229050D01*
Y225950D01*
X679387Y225450D01*
X678387D01*
X677887Y225950D01*
Y229050D01*
X677387Y229550D01*
X676387D01*
X675887Y229050D01*
Y225950D01*
X675387Y225450D01*
X674387D01*
X673887Y225950D01*
Y229050D01*
X673387Y229550D01*
X672387D01*
X671887Y229050D01*
Y225950D01*
X671387Y225450D01*
X670387D01*
X669887Y225950D01*
Y229050D01*
X669387Y229550D01*
X668387D01*
X667887Y229050D01*
Y225950D01*
X667387Y225450D01*
X663691D01*
X663191Y224950D01*
Y222600D01*
X662691Y222100D01*
X661691D01*
X661191Y222600D01*
Y224950D01*
X660691Y225450D01*
X659691D01*
X659191Y224950D01*
Y222600D01*
X658691Y222100D01*
X657691D01*
X657191Y222600D01*
Y224950D01*
X656691Y225450D01*
X655691D01*
X655191Y224950D01*
Y222600D01*
X654691Y222100D01*
X653691D01*
X653191Y222600D01*
Y224950D01*
X652691Y225450D01*
X651350D01*
X650850Y224950D01*
Y222495D01*
X650350Y221995D01*
X646957D01*
X642562Y217600D01*
X640400D01*
G01X703979Y219995D02*
X702272D01*
X701772Y220495D01*
Y222950D01*
X701272Y223450D01*
X700272D01*
X699772Y222950D01*
Y220495D01*
X699272Y219995D01*
X698272D01*
X697772Y220495D01*
Y222950D01*
X697272Y223450D01*
X696272D01*
X695772Y222950D01*
Y220495D01*
X695272Y219995D01*
X694272D01*
X693772Y220495D01*
Y222950D01*
X693272Y223450D01*
X692272D01*
X691772Y222950D01*
Y220495D01*
X691272Y219995D01*
X690272D01*
X689772Y220495D01*
Y222950D01*
X689272Y223450D01*
X688272D01*
X687772Y222950D01*
Y220495D01*
X687272Y219995D01*
X686272D01*
X685772Y220495D01*
Y222950D01*
X685272Y223450D01*
X684272D01*
X683772Y222950D01*
Y220495D01*
X683272Y219995D01*
X682272D01*
X681772Y220495D01*
Y222950D01*
X681272Y223450D01*
X680272D01*
X679772Y222950D01*
Y220495D01*
X679272Y219995D01*
X678272D01*
X677772Y220495D01*
Y222950D01*
X677272Y223450D01*
X676272D01*
X675772Y222950D01*
Y220495D01*
X675272Y219995D01*
X674272D01*
X673772Y220495D01*
Y222950D01*
X673272Y223450D01*
X672272D01*
X671772Y222950D01*
Y220495D01*
X671272Y219995D01*
X670272D01*
X669772Y220495D01*
Y222950D01*
X669272Y223450D01*
X668272D01*
X667772Y222950D01*
Y220495D01*
X667272Y219995D01*
X647786D01*
X643171Y215380D01*
X638703D01*
X636491Y217592D01*
G01X633092Y217496D02*
X637208Y213380D01*
X644000D01*
X648370Y217750D01*
X700248D01*
X700748Y217250D01*
Y215050D01*
X701248Y214550D01*
X702248D01*
X702748Y215050D01*
Y217250D01*
X703248Y217750D01*
X704248D01*
X704748Y217250D01*
Y215050D01*
X705248Y214550D01*
X706248D01*
X706748Y215050D01*
Y217250D01*
X707248Y217750D01*
X711252D01*
X711752Y217250D01*
Y214400D01*
X712252Y213900D01*
X713252D01*
X713752Y214400D01*
Y217250D01*
X714252Y217750D01*
X715252D01*
X715752Y217250D01*
Y214400D01*
X716252Y213900D01*
X717252D01*
X717752Y214400D01*
Y217250D01*
X718252Y217750D01*
X719252D01*
X719752Y217250D01*
Y214400D01*
X720252Y213900D01*
X721252D01*
X721752Y214400D01*
Y217250D01*
X722252Y217750D01*
X728314D01*
X730709Y215355D01*
G01X740158D02*
X735359Y210556D01*
X710756D01*
X708700Y208500D01*
X696421D01*
X695471Y209450D01*
X687184D01*
X686684Y208950D01*
Y201150D01*
X686184Y200650D01*
X685184D01*
X684684Y201150D01*
Y208950D01*
X684184Y209450D01*
X683184D01*
X682684Y208950D01*
Y202390D01*
X682194Y201900D01*
X681319D01*
X680684Y202535D01*
Y208950D01*
X680184Y209450D01*
X679184D01*
X678684Y208950D01*
Y203800D01*
X678184Y203300D01*
X677184D01*
X676684Y203800D01*
Y208950D01*
X676184Y209450D01*
X675184D01*
X674684Y208950D01*
Y205650D01*
X674184Y205150D01*
X673184D01*
X672684Y205650D01*
Y208950D01*
X672184Y209450D01*
X663650D01*
X659500Y205300D01*
G01X665500Y201900D02*
X673200Y194200D01*
X729110D01*
X740969Y206059D01*
X743008D01*
G01X703320Y203900D02*
X698070Y198650D01*
X681740D01*
X679640Y200750D01*
X674399D01*
X667700Y207450D01*
X665050D01*
X662900Y205300D01*
G01X645400Y264050D02*
Y260433D01*
X632967Y248000D01*
X628073D01*
X626693Y249380D01*
X625159D01*
X623700Y247921D01*
Y220383D01*
X632703Y211380D01*
X647284D01*
X649497Y213593D01*
X692927D01*
X694720Y211800D01*
X695950D01*
X697250Y210500D01*
X709427D01*
X711133Y212206D01*
X733859D01*
G01X654600Y367600D02*
X654824Y367376D01*
Y329376D01*
X660700Y323500D01*
Y292200D01*
G01X639318Y354003D02*
Y322599D01*
X634000Y317281D01*
Y293573D01*
X634826Y292747D01*
Y292099D01*
X634830Y292095D01*
G01X638453Y291949D02*
X636000Y294402D01*
Y316452D01*
X643082Y323534D01*
Y353941D01*
G01X607800Y382362D02*
X605950Y380512D01*
X605951Y363827D01*
Y361757D01*
X604589Y360395D01*
Y353711D01*
X607100Y351200D01*
G01X718098Y259423D02*
X718900D01*
X720576Y261099D01*
X722733D01*
X723204Y261570D01*
X731480D01*
X733290Y259760D01*
X738280D01*
X740530Y262010D01*
G01X693800Y264300D02*
Y276706D01*
X683650Y286855D01*
Y288717D01*
X682567Y289800D01*
X680706D01*
X679350Y291156D01*
Y391277D01*
X691873Y403800D01*
G01X732264Y204312D02*
X732262Y204314D01*
Y204387D01*
X730049Y206600D01*
X725400D01*
X724200Y205400D01*
X708400D01*
X706900Y203900D01*
X703320D01*
G01X721504Y402321D02*
Y389296D01*
X733250Y377550D01*
Y323650D01*
X722468Y312868D01*
Y308964D01*
G01X675555Y318736D02*
X675450Y318841D01*
Y392657D01*
X689577Y406784D01*
X691387D01*
X691813Y407210D01*
G01X672350Y317600D02*
X672749Y317999D01*
Y319278D01*
X673450Y319979D01*
Y393886D01*
X690305Y410741D01*
X691874D01*
G01X737009Y284646D02*
X732754Y288901D01*
X724118D01*
X722759Y290260D01*
Y291921D01*
X716300Y298380D01*
Y331340D01*
G01X718300Y362900D02*
Y363715D01*
X709006Y373009D01*
Y410206D01*
G01X780815Y47062D02*
X782150Y48397D01*
Y87850D01*
X779000Y91000D01*
X769500D01*
G01X762765Y42200D02*
X780200D01*
X784350Y46350D01*
Y85450D01*
X792600Y93700D01*
Y101300D01*
G01X763825Y89975D02*
X763875Y90025D01*
X767775D01*
X771400Y86400D01*
X772800D01*
X776500Y82700D01*
G01X744400Y322800D02*
X743617Y323583D01*
Y325517D01*
X739340Y329794D01*
Y343554D01*
X742050Y346265D01*
Y366101D01*
X753730Y377781D01*
X790357D01*
G01X735300Y401957D02*
X735750Y401507D01*
Y331262D01*
X740400Y326612D01*
Y318744D01*
X746531Y312613D01*
Y297318D01*
X746456Y297243D01*
G54D12*
X168898Y548819D03*
X175197Y589764D03*
X172048D03*
X168898D03*
X165748Y583464D03*
X159449Y561417D03*
X172047D03*
X168898Y558268D03*
X159449Y555118D03*
Y586614D03*
X162598Y580315D03*
X165748Y586614D03*
X156299Y577165D03*
X159449Y580315D03*
X162598Y583464D03*
X165748Y567717D03*
X197243Y551970D03*
X194093D03*
X184646Y548821D03*
X159449Y542521D03*
X181497Y545671D03*
X209842Y545669D03*
X165749Y548819D03*
X181496Y542520D03*
X159449Y548821D03*
X172047Y548819D03*
X168898Y551969D03*
X162599Y548821D03*
X168898Y555119D03*
X181497Y548821D03*
X178346Y545670D03*
X203542Y548821D03*
X197244Y586615D03*
X200393Y586614D03*
Y592913D03*
X159448D03*
X162598Y589764D03*
X165748D03*
Y592913D03*
X181497D03*
X197244Y545669D03*
X194094Y548820D03*
X156300Y539371D03*
X194093Y596063D03*
X184645Y599213D03*
X203542D03*
X206692Y602362D03*
X203542Y596063D03*
X178347Y599213D03*
X181496Y596062D03*
X209841Y599212D03*
X206692Y599213D03*
X165748Y596063D03*
X175197D03*
Y599213D03*
X172048D03*
X219800Y445700D03*
X213874Y445226D03*
X212992Y561417D03*
Y551969D03*
X216141Y551970D03*
X212992Y548819D03*
X781088Y294094D03*
X771653Y294093D03*
G54D22*
G01X13215Y-125739D02*
X14089Y-124864D01*
X14744Y-123406D01*
X15181Y-121363D01*
X14744Y-119614D01*
X13871Y-118447D01*
X12342Y-117572D01*
X6447D01*
Y-135072D01*
X13652D01*
X15181Y-133906D01*
X16054Y-132155D01*
X16491Y-130114D01*
X16054Y-128072D01*
X14744Y-126322D01*
X13215Y-125739D01*
X6447D01*
G01X25912Y-135072D02*
Y-123406D01*
G01Y-125739D02*
X27004Y-124572D01*
X28096Y-123697D01*
X29624Y-123406D01*
X30715Y-123697D01*
X32026Y-124572D01*
G01X41884Y-140322D02*
X43194Y-140905D01*
X44941Y-140322D01*
X46032Y-139156D01*
X46906Y-137697D01*
X48215Y-133031D01*
X51054Y-123406D01*
G01X44067D02*
X48215Y-133031D01*
G01X67462Y-124864D02*
X65934Y-123697D01*
X64624Y-123406D01*
X62877Y-123989D01*
X61567Y-125155D01*
X60694Y-127197D01*
X60475Y-129239D01*
X60694Y-131281D01*
X61567Y-133031D01*
X62877Y-134489D01*
X64624Y-135072D01*
X66152Y-134489D01*
X67462Y-133322D01*
G01X78194Y-127197D02*
X85181D01*
X84526Y-125155D01*
X83434Y-123989D01*
X81906Y-123406D01*
X80377Y-123697D01*
X79067Y-124572D01*
X78194Y-126614D01*
X77757Y-128364D01*
Y-130114D01*
X78194Y-131864D01*
X79286Y-133614D01*
X80596Y-134780D01*
X82124Y-135072D01*
X83652Y-134489D01*
X85181Y-132739D01*
G01X121272Y-119031D02*
X119962Y-118155D01*
X118434Y-117572D01*
X116687D01*
X114722Y-118447D01*
X113194Y-119905D01*
X112102Y-121656D01*
X111229Y-124572D01*
X111010Y-127197D01*
X111447Y-129822D01*
X112102Y-131572D01*
X113412Y-133322D01*
X114941Y-134489D01*
X116469Y-135072D01*
X117997D01*
X119526Y-134489D01*
X120836Y-133614D01*
X121928Y-132448D01*
G01X137899Y-135072D02*
Y-123406D01*
G01Y-125447D02*
X137026Y-124281D01*
X135715Y-123697D01*
X134187Y-123406D01*
X132659Y-123989D01*
X131349Y-125155D01*
X130475Y-126905D01*
X130039Y-129239D01*
X130475Y-131572D01*
X131349Y-133322D01*
X132659Y-134489D01*
X134187Y-135072D01*
X135715Y-134780D01*
X137026Y-133906D01*
X137899Y-132739D01*
G01X147757Y-135072D02*
Y-123406D01*
G01Y-126322D02*
X148631Y-124864D01*
X149941Y-123697D01*
X151687Y-123406D01*
X153215Y-123697D01*
X154526Y-124864D01*
X155181Y-126905D01*
Y-135072D01*
G01X164384Y-140322D02*
X165694Y-140905D01*
X167441Y-140322D01*
X168532Y-139156D01*
X169406Y-137697D01*
X170715Y-133031D01*
X173554Y-123406D01*
G01X166567D02*
X170715Y-133031D01*
G01X186469Y-135072D02*
X185159Y-134780D01*
X183849Y-133614D01*
X182975Y-131572D01*
X182539Y-129239D01*
X182975Y-126905D01*
X183849Y-124864D01*
X185159Y-123697D01*
X186469Y-123406D01*
X187779Y-123697D01*
X189089Y-124864D01*
X189962Y-126905D01*
X190181Y-129239D01*
X189962Y-131572D01*
X189089Y-133614D01*
X187779Y-134780D01*
X186469Y-135072D01*
G01X200257D02*
Y-123406D01*
G01Y-126322D02*
X201131Y-124864D01*
X202441Y-123697D01*
X204187Y-123406D01*
X205715Y-123697D01*
X207026Y-124864D01*
X207681Y-126905D01*
Y-135072D01*
G01X236349Y-117572D02*
X241589D01*
G01X238969D02*
Y-135072D01*
G01X236349D02*
X241589D01*
G01X256469D02*
X254722Y-134780D01*
X253194Y-133614D01*
X251884Y-131864D01*
X251010Y-129822D01*
X250574Y-127489D01*
Y-125155D01*
X251010Y-122822D01*
X251884Y-120780D01*
X253194Y-119031D01*
X254722Y-117864D01*
X256469Y-117572D01*
X258215Y-117864D01*
X259744Y-119031D01*
X261054Y-120780D01*
X261928Y-122822D01*
X262364Y-125155D01*
Y-127489D01*
X261928Y-129822D01*
X261054Y-131864D01*
X259744Y-133614D01*
X258215Y-134780D01*
X256469Y-135072D01*
G01X268292D02*
Y-117572D01*
X273969Y-132155D01*
X279646Y-117572D01*
Y-135072D01*
G01X307877Y-140905D02*
X305694Y-137989D01*
X304602Y-135072D01*
Y-123406D01*
X305694Y-120489D01*
X307877Y-117572D01*
G01X321010Y-123406D02*
X323631Y-135072D01*
X326469Y-123406D01*
X329307Y-135072D01*
X331928Y-123406D01*
G01X340039Y-135655D02*
X347899Y-117572D01*
G01X376349D02*
X381589D01*
G01X378969D02*
Y-135072D01*
G01X376349D02*
X381589D01*
G01X396469D02*
X394722Y-134780D01*
X393194Y-133614D01*
X391884Y-131864D01*
X391010Y-129822D01*
X390574Y-127489D01*
Y-125155D01*
X391010Y-122822D01*
X391884Y-120780D01*
X393194Y-119031D01*
X394722Y-117864D01*
X396469Y-117572D01*
X398215Y-117864D01*
X399744Y-119031D01*
X401054Y-120780D01*
X401928Y-122822D01*
X402364Y-125155D01*
Y-127489D01*
X401928Y-129822D01*
X401054Y-131864D01*
X399744Y-133614D01*
X398215Y-134780D01*
X396469Y-135072D01*
G01X418772Y-119031D02*
X417462Y-118155D01*
X415934Y-117572D01*
X414187D01*
X412222Y-118447D01*
X410694Y-119905D01*
X409602Y-121656D01*
X408729Y-124572D01*
X408510Y-127197D01*
X408947Y-129822D01*
X409602Y-131572D01*
X410912Y-133322D01*
X412441Y-134489D01*
X413969Y-135072D01*
X415497D01*
X417026Y-134489D01*
X418336Y-133614D01*
X419428Y-132448D01*
G01X432561Y-140905D02*
X434744Y-137989D01*
X435836Y-135072D01*
Y-123406D01*
X434744Y-120489D01*
X432561Y-117572D01*
G01X180792Y-90072D02*
Y-72572D01*
X186469Y-87155D01*
X192146Y-72572D01*
Y-90072D01*
G01X203969D02*
X202659Y-89780D01*
X201349Y-88614D01*
X200475Y-86572D01*
X200039Y-84239D01*
X200475Y-81905D01*
X201349Y-79864D01*
X202659Y-78697D01*
X203969Y-78406D01*
X205279Y-78697D01*
X206589Y-79864D01*
X207462Y-81905D01*
X207681Y-84239D01*
X207462Y-86572D01*
X206589Y-88614D01*
X205279Y-89780D01*
X203969Y-90072D01*
G01X225399Y-72572D02*
Y-90072D01*
G01Y-87448D02*
X224526Y-88906D01*
X223215Y-89780D01*
X221687Y-90072D01*
X219941Y-89489D01*
X218631Y-88031D01*
X217757Y-86281D01*
X217539Y-84239D01*
X217757Y-82197D01*
X218631Y-80447D01*
X219941Y-78989D01*
X221687Y-78406D01*
X223215Y-78697D01*
X224307Y-79281D01*
X225399Y-80447D01*
G01X235694Y-82197D02*
X242681D01*
X242026Y-80155D01*
X240934Y-78989D01*
X239406Y-78406D01*
X237877Y-78697D01*
X236567Y-79572D01*
X235694Y-81614D01*
X235257Y-83364D01*
Y-85114D01*
X235694Y-86864D01*
X236786Y-88614D01*
X238096Y-89780D01*
X239624Y-90072D01*
X241152Y-89489D01*
X242681Y-87739D01*
G01X256469Y-90072D02*
Y-72572D01*
G01X490269Y-135072D02*
Y-117572D01*
X487649Y-121072D01*
G01Y-135072D02*
X492889D01*
G01X503621Y-127781D02*
X505149Y-125739D01*
X506459Y-124572D01*
X508206Y-123989D01*
X509734Y-124572D01*
X510826Y-125739D01*
X511699Y-127489D01*
X511917Y-129530D01*
X511699Y-131281D01*
X510826Y-133031D01*
X509515Y-134489D01*
X507987Y-135072D01*
X506241Y-134489D01*
X504712Y-132739D01*
X503839Y-130114D01*
X503621Y-127197D01*
X504057Y-123406D01*
X504712Y-121363D01*
X505804Y-119322D01*
X507332Y-117864D01*
X508861Y-117572D01*
X510389Y-118155D01*
X511481Y-119614D01*
G01X520466Y-131572D02*
X521775Y-133614D01*
X523522Y-134780D01*
X525487Y-135072D01*
X527234Y-134780D01*
X528981Y-133322D01*
X530072Y-131572D01*
X530291Y-129822D01*
X529854Y-127781D01*
X528326Y-126322D01*
X526797Y-125739D01*
X524832D01*
G01X526797D02*
X528107Y-124864D01*
X529199Y-123406D01*
X529636Y-121656D01*
X529199Y-119905D01*
X528107Y-118447D01*
X526142Y-117572D01*
X524177Y-117864D01*
X522212Y-119031D01*
G01X542769Y-135072D02*
Y-117572D01*
X540149Y-121072D01*
G01Y-135072D02*
X545389D01*
G01X560269D02*
X561797Y-134780D01*
X563544Y-133906D01*
X564636Y-132448D01*
X565072Y-130405D01*
X564636Y-128364D01*
X563326Y-126614D01*
X561361Y-125739D01*
X559177D01*
X557867Y-125155D01*
X556775Y-123697D01*
X556339Y-121656D01*
X556994Y-119614D01*
X558522Y-118155D01*
X560269Y-117572D01*
X562015Y-118155D01*
X563544Y-119614D01*
X564199Y-121656D01*
X563762Y-123697D01*
X562671Y-125155D01*
X561361Y-125739D01*
X559177D01*
X557212Y-126614D01*
X555902Y-128364D01*
X555466Y-130405D01*
X555902Y-132448D01*
X556994Y-133906D01*
X558741Y-134780D01*
X560269Y-135072D01*
G01X477152Y-90072D02*
Y-72572D01*
X482392D01*
X484139Y-73447D01*
X485449Y-75489D01*
X485886Y-77822D01*
X485449Y-80155D01*
X484357Y-81905D01*
X482392Y-82781D01*
X477152D01*
G01X503822Y-74031D02*
X502512Y-73155D01*
X500984Y-72572D01*
X499237D01*
X497272Y-73447D01*
X495744Y-74905D01*
X494652Y-76656D01*
X493779Y-79572D01*
X493560Y-82197D01*
X493997Y-84822D01*
X494652Y-86572D01*
X495962Y-88322D01*
X497491Y-89489D01*
X499019Y-90072D01*
X500547D01*
X502076Y-89489D01*
X503386Y-88614D01*
X504478Y-87448D01*
G01X518265Y-80739D02*
X519139Y-79864D01*
X519794Y-78406D01*
X520231Y-76363D01*
X519794Y-74614D01*
X518921Y-73447D01*
X517392Y-72572D01*
X511497D01*
Y-90072D01*
X518702D01*
X520231Y-88906D01*
X521104Y-87155D01*
X521541Y-85114D01*
X521104Y-83072D01*
X519794Y-81322D01*
X518265Y-80739D01*
X511497D01*
G01X527469Y-95905D02*
X540569D01*
G01X546497Y-90072D02*
Y-72572D01*
X556541Y-90072D01*
Y-72572D01*
G01X569019Y-90072D02*
X567272Y-89780D01*
X565744Y-88614D01*
X564434Y-86864D01*
X563560Y-84822D01*
X563124Y-82489D01*
Y-80155D01*
X563560Y-77822D01*
X564434Y-75780D01*
X565744Y-74031D01*
X567272Y-72864D01*
X569019Y-72572D01*
X570765Y-72864D01*
X572294Y-74031D01*
X573604Y-75780D01*
X574478Y-77822D01*
X574914Y-80155D01*
Y-82489D01*
X574478Y-84822D01*
X573604Y-86864D01*
X572294Y-88614D01*
X570765Y-89780D01*
X569019Y-90072D01*
G01X647421Y-120489D02*
X648731Y-118739D01*
X650259Y-117864D01*
X652006Y-117572D01*
X654189Y-118155D01*
X655717Y-119614D01*
X656154Y-121363D01*
X655936Y-123114D01*
X655062Y-124572D01*
X650696Y-127489D01*
X648731Y-129530D01*
X647421Y-132448D01*
X646984Y-135072D01*
X656154D01*
G01X619860Y-72572D02*
X625319Y-90072D01*
X630778Y-72572D01*
G01X647186Y-90072D02*
X638452D01*
Y-72572D01*
X647186D01*
G01X643692Y-81030D02*
X638452D01*
G01X655952Y-90072D02*
Y-72572D01*
X661411D01*
X663157Y-73447D01*
X664249Y-74614D01*
X664686Y-76947D01*
X664249Y-79281D01*
X662939Y-80739D01*
X661411Y-81614D01*
X655952D01*
G01X661411D02*
X664686Y-90072D01*
G01X677819Y-90655D02*
X677382Y-90364D01*
Y-89780D01*
X677819Y-89489D01*
X678256Y-89780D01*
Y-90364D01*
X677819Y-90655D01*
G01X779652Y-117572D02*
Y-135072D01*
X788386D01*
G01X796716Y-131572D02*
X798025Y-133614D01*
X799772Y-134780D01*
X801737Y-135072D01*
X803484Y-134780D01*
X805231Y-133322D01*
X806322Y-131572D01*
X806541Y-129822D01*
X806104Y-127781D01*
X804576Y-126322D01*
X803047Y-125739D01*
X801082D01*
G01X803047D02*
X804357Y-124864D01*
X805449Y-123406D01*
X805886Y-121656D01*
X805449Y-119905D01*
X804357Y-118447D01*
X802392Y-117572D01*
X800427Y-117864D01*
X798462Y-119031D01*
G01X753402Y-72572D02*
Y-90072D01*
X762136D01*
G01X779199D02*
Y-78406D01*
G01Y-80447D02*
X778326Y-79281D01*
X777015Y-78697D01*
X775487Y-78406D01*
X773959Y-78989D01*
X772649Y-80155D01*
X771775Y-81905D01*
X771339Y-84239D01*
X771775Y-86572D01*
X772649Y-88322D01*
X773959Y-89489D01*
X775487Y-90072D01*
X777015Y-89780D01*
X778326Y-88906D01*
X779199Y-87739D01*
G01X788184Y-95322D02*
X789494Y-95905D01*
X791241Y-95322D01*
X792332Y-94156D01*
X793206Y-92697D01*
X794515Y-88031D01*
X797354Y-78406D01*
G01X790367D02*
X794515Y-88031D01*
G01X806994Y-82197D02*
X813981D01*
X813326Y-80155D01*
X812234Y-78989D01*
X810706Y-78406D01*
X809177Y-78697D01*
X807867Y-79572D01*
X806994Y-81614D01*
X806557Y-83364D01*
Y-85114D01*
X806994Y-86864D01*
X808086Y-88614D01*
X809396Y-89780D01*
X810924Y-90072D01*
X812452Y-89489D01*
X813981Y-87739D01*
G01X824712Y-90072D02*
Y-78406D01*
G01Y-80739D02*
X825804Y-79572D01*
X826896Y-78697D01*
X828424Y-78406D01*
X829515Y-78697D01*
X830826Y-79572D01*
G01X917819Y-135072D02*
X916072Y-134780D01*
X914544Y-133614D01*
X913234Y-131864D01*
X912360Y-129822D01*
X911924Y-127489D01*
Y-125155D01*
X912360Y-122822D01*
X913234Y-120780D01*
X914544Y-119031D01*
X916072Y-117864D01*
X917819Y-117572D01*
X919565Y-117864D01*
X921094Y-119031D01*
X922404Y-120780D01*
X923278Y-122822D01*
X923714Y-125155D01*
Y-127489D01*
X923278Y-129822D01*
X922404Y-131864D01*
X921094Y-133614D01*
X919565Y-134780D01*
X917819Y-135072D01*
G01X919565Y-130405D02*
X922186Y-135072D01*
G01X930516Y-117572D02*
Y-130114D01*
X931389Y-132739D01*
X933136Y-134489D01*
X935319Y-135072D01*
X937502Y-134489D01*
X939249Y-132739D01*
X940122Y-130114D01*
Y-117572D01*
G01X950199D02*
X955439D01*
G01X952819D02*
Y-135072D01*
G01X950199D02*
X955439D01*
G01X965297D02*
Y-117572D01*
X975341Y-135072D01*
Y-117572D01*
G01X992622Y-119031D02*
X991312Y-118155D01*
X989784Y-117572D01*
X988037D01*
X986072Y-118447D01*
X984544Y-119905D01*
X983452Y-121656D01*
X982579Y-124572D01*
X982360Y-127197D01*
X982797Y-129822D01*
X983452Y-131572D01*
X984762Y-133322D01*
X986291Y-134489D01*
X987819Y-135072D01*
X989347D01*
X990876Y-134489D01*
X992186Y-133614D01*
X993278Y-132448D01*
G01X1005319Y-135072D02*
Y-127197D01*
X1000952Y-117572D01*
G01X1009686D02*
X1005319Y-127197D01*
G01X895516Y-90072D02*
Y-72572D01*
X899882D01*
X901629Y-73447D01*
X902939Y-74614D01*
X904031Y-76363D01*
X904904Y-78406D01*
X905122Y-81322D01*
X904904Y-84239D01*
X904031Y-86281D01*
X902939Y-88031D01*
X901629Y-89197D01*
X899882Y-90072D01*
X895516D01*
G01X914544Y-82197D02*
X921531D01*
X920876Y-80155D01*
X919784Y-78989D01*
X918256Y-78406D01*
X916727Y-78697D01*
X915417Y-79572D01*
X914544Y-81614D01*
X914107Y-83364D01*
Y-85114D01*
X914544Y-86864D01*
X915636Y-88614D01*
X916946Y-89780D01*
X918474Y-90072D01*
X920002Y-89489D01*
X921531Y-87739D01*
G01X932044Y-88031D02*
X933136Y-89197D01*
X934664Y-90072D01*
X935974D01*
X937284Y-89489D01*
X938157Y-88614D01*
X938594Y-87448D01*
X938376Y-85697D01*
X937502Y-84822D01*
X933572Y-83072D01*
X932699Y-81030D01*
X933136Y-79572D01*
X934009Y-78697D01*
X935319Y-78406D01*
X936629Y-78697D01*
X937939Y-79572D01*
G01X952819Y-78406D02*
Y-90072D01*
G01Y-73739D02*
X952382Y-73447D01*
Y-72864D01*
X952819Y-72572D01*
X953256Y-72864D01*
Y-73447D01*
X952819Y-73739D01*
G01X967262Y-94447D02*
X968791Y-95614D01*
X970537Y-95905D01*
X972065Y-95614D01*
X973376Y-94156D01*
X974249Y-92114D01*
Y-78406D01*
G01Y-80739D02*
X973376Y-79572D01*
X972065Y-78697D01*
X970537Y-78406D01*
X968791Y-78989D01*
X967699Y-80155D01*
X966825Y-82197D01*
X966389Y-84239D01*
X966607Y-85989D01*
X967481Y-88031D01*
X968791Y-89489D01*
X970537Y-90072D01*
X971847Y-89780D01*
X973376Y-88614D01*
X974249Y-87448D01*
G01X984107Y-90072D02*
Y-78406D01*
G01Y-81322D02*
X984981Y-79864D01*
X986291Y-78697D01*
X988037Y-78406D01*
X989565Y-78697D01*
X990876Y-79864D01*
X991531Y-81905D01*
Y-90072D01*
G01X1002044Y-82197D02*
X1009031D01*
X1008376Y-80155D01*
X1007284Y-78989D01*
X1005756Y-78406D01*
X1004227Y-78697D01*
X1002917Y-79572D01*
X1002044Y-81614D01*
X1001607Y-83364D01*
Y-85114D01*
X1002044Y-86864D01*
X1003136Y-88614D01*
X1004446Y-89780D01*
X1005974Y-90072D01*
X1007502Y-89489D01*
X1009031Y-87739D01*
G01X1019762Y-90072D02*
Y-78406D01*
G01Y-80739D02*
X1020854Y-79572D01*
X1021946Y-78697D01*
X1023474Y-78406D01*
X1024565Y-78697D01*
X1025876Y-79572D01*
G01X1066519Y-117572D02*
X1064772Y-118155D01*
X1063462Y-119614D01*
X1062589Y-121363D01*
X1061934Y-123697D01*
X1061716Y-126322D01*
X1061934Y-128947D01*
X1062589Y-131281D01*
X1063462Y-133031D01*
X1064772Y-134489D01*
X1066519Y-135072D01*
X1068265Y-134489D01*
X1069576Y-133031D01*
X1070449Y-131281D01*
X1071104Y-128947D01*
X1071322Y-126322D01*
X1071104Y-123697D01*
X1070449Y-121363D01*
X1069576Y-119614D01*
X1068265Y-118155D01*
X1066519Y-117572D01*
G01X1084019Y-135072D02*
X1085547Y-134780D01*
X1087294Y-133906D01*
X1088386Y-132448D01*
X1088822Y-130405D01*
X1088386Y-128364D01*
X1087076Y-126614D01*
X1085111Y-125739D01*
X1082927D01*
X1081617Y-125155D01*
X1080525Y-123697D01*
X1080089Y-121656D01*
X1080744Y-119614D01*
X1082272Y-118155D01*
X1084019Y-117572D01*
X1085765Y-118155D01*
X1087294Y-119614D01*
X1087949Y-121656D01*
X1087512Y-123697D01*
X1086421Y-125155D01*
X1085111Y-125739D01*
X1082927D01*
X1080962Y-126614D01*
X1079652Y-128364D01*
X1079216Y-130405D01*
X1079652Y-132448D01*
X1080744Y-133906D01*
X1082491Y-134780D01*
X1084019Y-135072D01*
G01X1097589Y-135655D02*
X1105449Y-117572D01*
G01X1119019D02*
X1117272Y-118155D01*
X1115962Y-119614D01*
X1115089Y-121363D01*
X1114434Y-123697D01*
X1114216Y-126322D01*
X1114434Y-128947D01*
X1115089Y-131281D01*
X1115962Y-133031D01*
X1117272Y-134489D01*
X1119019Y-135072D01*
X1120765Y-134489D01*
X1122076Y-133031D01*
X1122949Y-131281D01*
X1123604Y-128947D01*
X1123822Y-126322D01*
X1123604Y-123697D01*
X1122949Y-121363D01*
X1122076Y-119614D01*
X1120765Y-118155D01*
X1119019Y-117572D01*
G01X1136082Y-135072D02*
X1136519Y-131281D01*
X1137174Y-128072D01*
X1138047Y-125155D01*
X1139139Y-121947D01*
X1140886Y-117572D01*
X1132152D01*
G01X1150089Y-135655D02*
X1157949Y-117572D01*
G01X1167371Y-120489D02*
X1168681Y-118739D01*
X1170209Y-117864D01*
X1171956Y-117572D01*
X1174139Y-118155D01*
X1175667Y-119614D01*
X1176104Y-121363D01*
X1175886Y-123114D01*
X1175012Y-124572D01*
X1170646Y-127489D01*
X1168681Y-129530D01*
X1167371Y-132448D01*
X1166934Y-135072D01*
X1176104D01*
G01X1189019Y-117572D02*
X1187272Y-118155D01*
X1185962Y-119614D01*
X1185089Y-121363D01*
X1184434Y-123697D01*
X1184216Y-126322D01*
X1184434Y-128947D01*
X1185089Y-131281D01*
X1185962Y-133031D01*
X1187272Y-134489D01*
X1189019Y-135072D01*
X1190765Y-134489D01*
X1192076Y-133031D01*
X1192949Y-131281D01*
X1193604Y-128947D01*
X1193822Y-126322D01*
X1193604Y-123697D01*
X1192949Y-121363D01*
X1192076Y-119614D01*
X1190765Y-118155D01*
X1189019Y-117572D01*
G01X1206519Y-135072D02*
Y-117572D01*
X1203899Y-121072D01*
G01Y-135072D02*
X1209139D01*
G01X1223582D02*
X1224019Y-131281D01*
X1224674Y-128072D01*
X1225547Y-125155D01*
X1226639Y-121947D01*
X1228386Y-117572D01*
X1219652D01*
G01X1114216Y-90072D02*
Y-72572D01*
X1118582D01*
X1120329Y-73447D01*
X1121639Y-74614D01*
X1122731Y-76363D01*
X1123604Y-78406D01*
X1123822Y-81322D01*
X1123604Y-84239D01*
X1122731Y-86281D01*
X1121639Y-88031D01*
X1120329Y-89197D01*
X1118582Y-90072D01*
X1114216D01*
G01X1140449D02*
Y-78406D01*
G01Y-80447D02*
X1139576Y-79281D01*
X1138265Y-78697D01*
X1136737Y-78406D01*
X1135209Y-78989D01*
X1133899Y-80155D01*
X1133025Y-81905D01*
X1132589Y-84239D01*
X1133025Y-86572D01*
X1133899Y-88322D01*
X1135209Y-89489D01*
X1136737Y-90072D01*
X1138265Y-89780D01*
X1139576Y-88906D01*
X1140449Y-87739D01*
G01X1154019Y-72572D02*
Y-90072D01*
G01X1150962Y-78406D02*
X1157076D01*
G01X1168244Y-82197D02*
X1175231D01*
X1174576Y-80155D01*
X1173484Y-78989D01*
X1171956Y-78406D01*
X1170427Y-78697D01*
X1169117Y-79572D01*
X1168244Y-81614D01*
X1167807Y-83364D01*
Y-85114D01*
X1168244Y-86864D01*
X1169336Y-88614D01*
X1170646Y-89780D01*
X1172174Y-90072D01*
X1173702Y-89489D01*
X1175231Y-87739D01*
G54D13*
X316000Y671850D03*
X665500Y201900D03*
G54D23*
G01X194093Y596063D02*
X195750Y597720D01*
Y598535D01*
X198893Y601678D01*
Y606977D01*
X195000Y610870D01*
Y620449D01*
X203450Y628899D01*
Y640531D01*
X201591Y642390D01*
X201280D01*
X198989Y644681D01*
Y644711D01*
X195169D01*
X194490Y645390D01*
G54D14*
G01X659300Y373100D02*
X665248Y379048D01*
Y391498D01*
X694765Y421015D01*
Y444065D01*
X699900Y449200D01*
Y453600D01*
G01X696800Y476400D02*
Y476100D01*
X696700Y476000D01*
Y460700D01*
X699900Y457500D01*
Y453600D01*
G01X689100Y507900D02*
Y504775D01*
X696700Y497175D01*
Y476500D01*
X696800Y476400D01*
X428740Y154331D03*
X450000Y159055D03*
X457086Y154331D03*
X471260D03*
X421653Y164567D03*
X442913Y159843D03*
X450000Y164567D03*
X457086Y159843D03*
X471260D03*
X421653Y173229D03*
X457086Y168504D03*
X464173Y173229D03*
X421653Y178740D03*
X428740Y174016D03*
X442913D03*
X457086D03*
X464173Y178740D03*
X513779Y154331D03*
X520866Y159055D03*
X535039D03*
X513779Y159843D03*
X520866Y164567D03*
X527953Y159843D03*
X535039Y164567D03*
X520866Y173229D03*
Y178740D03*
X535039D03*
X542126Y154331D03*
Y159843D03*
X556299D03*
G54D24*
G01X86750Y539218D02*
X88325Y540793D01*
X91461D01*
G01X91687Y553767D02*
X91310Y553390D01*
X85173D01*
X83600Y551817D01*
G01Y564415D02*
X85175Y562840D01*
X91272D01*
X91287Y562855D01*
G01X92377Y565977D02*
X90565D01*
X90552Y565990D01*
X88325D01*
X86750Y564415D01*
G01X170373Y540800D02*
Y547344D01*
X168898Y548819D01*
G01X180021Y540900D02*
Y543131D01*
X180885Y543995D01*
X181907D01*
X182972Y545060D01*
Y546772D01*
X184646Y548446D01*
Y548821D01*
G01X172047Y548819D02*
X173522Y547344D01*
Y541100D01*
G01X167348Y550248D02*
X168898Y551798D01*
Y551969D01*
G01X205185Y543200D02*
Y547178D01*
X203542Y548821D01*
G01X197525Y537566D02*
X198719Y538760D01*
Y546280D01*
X196179Y548820D01*
X194094D01*
G01X740530Y262010D02*
X742706Y264186D01*
X743935D01*
X744858Y265109D01*
Y272713D01*
X741782Y275789D01*
Y283944D01*
X741733Y283993D01*
Y285299D01*
X742655Y286221D01*
X743961D01*
X744881Y287141D01*
Y309000D01*
G54D15*
X629921Y57874D03*
X708661D03*
G54D25*
G01X386759Y79693D02*
X388052Y78400D01*
Y76790D01*
X387066Y75804D01*
X381971D01*
X379300Y78475D01*
Y79522D01*
X378133Y80688D01*
X377087D01*
X375920Y81855D01*
Y82845D01*
X374754Y84011D01*
X373764D01*
X372597Y85178D01*
Y93895D01*
X358220Y108272D01*
Y147260D01*
X358920Y147960D01*
Y149610D01*
X358220Y150310D01*
Y151960D01*
X358920Y152660D01*
Y154310D01*
X358220Y155010D01*
Y156660D01*
X358920Y157360D01*
Y159010D01*
X358220Y159710D01*
Y161360D01*
X358920Y162060D01*
Y163710D01*
X358220Y164410D01*
Y172610D01*
X354747Y176083D01*
Y197653D01*
X352178Y200222D01*
Y210881D01*
X352878Y211581D01*
Y213231D01*
X352178Y213931D01*
Y215581D01*
X352878Y216281D01*
Y217931D01*
X352178Y218631D01*
Y220281D01*
X352878Y220981D01*
Y222631D01*
X352178Y223331D01*
Y241124D01*
X358633Y247579D01*
Y436381D01*
X344025Y450989D01*
Y486271D01*
X339975Y490321D01*
Y506977D01*
X338537Y508415D01*
Y521686D01*
X341100Y524249D01*
Y528060D01*
X345094Y532054D01*
Y546633D01*
X339790Y551937D01*
Y564302D01*
X337855Y566237D01*
Y575356D01*
X341126Y578627D01*
Y590402D01*
X346125Y595401D01*
Y597051D01*
X346825Y597751D01*
Y599401D01*
X346125Y600101D01*
Y601751D01*
X346825Y602451D01*
Y604101D01*
X346125Y604801D01*
Y606451D01*
X346825Y607151D01*
Y608801D01*
X346125Y609501D01*
Y620279D01*
X342620Y623784D01*
Y630240D01*
X343797Y631417D01*
G01X390456Y79693D02*
X389352Y78589D01*
Y76251D01*
X387605Y74504D01*
X381432D01*
X371297Y84639D01*
Y93356D01*
X356920Y107733D01*
Y172071D01*
X353447Y175544D01*
Y197114D01*
X350878Y199683D01*
Y241663D01*
X357333Y248118D01*
Y435842D01*
X342725Y450450D01*
Y485732D01*
X338675Y489782D01*
Y506438D01*
X337237Y507876D01*
Y522225D01*
X339800Y524788D01*
Y528599D01*
X343794Y532593D01*
Y546094D01*
X338490Y551398D01*
Y563763D01*
X336555Y565698D01*
Y575895D01*
X339826Y579166D01*
Y590941D01*
X344825Y595940D01*
Y619740D01*
X341320Y623245D01*
Y630197D01*
X340100Y631417D01*
G54D16*
X651575Y20039D03*
X608267D03*
X641732Y126811D03*
X624015D03*
X651575Y72441D03*
X608267D03*
X730315Y20039D03*
X687007D03*
X720472Y126811D03*
X702755D03*
X730315Y72441D03*
X687007D03*
G54D26*
G01X122600Y557480D02*
X120480Y555360D01*
X113410D01*
X107395Y549345D01*
G54D17*
G01X134223Y691027D02*
X141284Y698088D01*
X152004D01*
X154764Y700848D01*
Y706562D01*
X159417Y711215D01*
X162100D01*
G01X195900Y649350D02*
Y654000D01*
X200700Y658800D01*
Y666799D01*
X206500Y672599D01*
Y688600D01*
X200400Y694700D01*
G01X275100Y460300D02*
Y453100D01*
X279974Y448226D01*
X287260D01*
X287261Y448227D01*
X289331D01*
X289332Y448226D01*
X291563D01*
X308939Y430850D01*
X322984D01*
X333499Y420335D01*
Y406499D01*
X322900Y395900D01*
X315172D01*
X311900Y392628D01*
Y383800D01*
X315200Y380500D01*
X320800D01*
X323982Y377318D01*
Y274382D01*
X318882Y269282D01*
Y195318D01*
X321298Y192902D01*
Y167338D01*
X327500Y161136D01*
Y143284D01*
X308011Y123795D01*
Y38950D01*
X310720Y36241D01*
Y32707D01*
X323727Y19700D01*
X327646D01*
X333476Y13870D01*
X552716D01*
X557751Y18905D01*
Y31717D01*
X562000Y35966D01*
Y81165D01*
X579000Y98165D01*
Y177785D01*
X587351Y186136D01*
Y341969D01*
X590272Y344890D01*
Y376113D01*
X595347Y381188D01*
Y404074D01*
X587930Y411491D01*
Y536100D01*
X613080Y561250D01*
X614000D01*
G01X717450Y551554D02*
X712454D01*
X712100Y551200D01*
X702850D01*
X683650Y532000D01*
X651764D01*
X592930Y473166D01*
Y415899D01*
X602098Y406731D01*
Y390100D01*
X600350Y388352D01*
Y366945D01*
X595663Y362258D01*
Y340063D01*
X593846Y338246D01*
Y185559D01*
X584470Y176183D01*
Y96563D01*
X571432Y83525D01*
Y38326D01*
X570108Y37002D01*
Y17862D01*
X561116Y8870D01*
X331404D01*
X325574Y14700D01*
X321655D01*
X305720Y30635D01*
Y34169D01*
X302856Y37033D01*
Y126848D01*
X322373Y146365D01*
Y159191D01*
X316298Y165266D01*
Y189902D01*
X312900Y193300D01*
Y213100D01*
X309832Y216168D01*
Y363868D01*
X306600Y367100D01*
Y374729D01*
X300429Y380900D01*
Y388229D01*
X313200Y401000D01*
X320707D01*
X328499Y408792D01*
Y418263D01*
X320912Y425850D01*
X306867D01*
X290267Y442450D01*
X275350D01*
X263750Y454050D01*
Y472768D01*
X270050Y479068D01*
Y481931D01*
X267524Y484457D01*
Y529859D01*
X263357Y534026D01*
Y545949D01*
X265316Y547908D01*
Y555567D01*
X265300Y555583D01*
Y570017D01*
X268350Y573067D01*
Y595361D01*
X264400Y599311D01*
Y645216D01*
X279200Y660016D01*
Y671600D01*
X271500Y679300D01*
Y693200D01*
X264700Y700000D01*
G01X290000Y727000D02*
X287136D01*
X274550Y714414D01*
Y682220D01*
X278200Y678570D01*
Y676500D01*
X282500Y672200D01*
Y659780D01*
X275050Y652330D01*
Y644700D01*
X271614Y641264D01*
Y628788D01*
X274152Y626250D01*
X279450D01*
X284600Y621100D01*
Y618050D01*
X286595Y616055D01*
Y610796D01*
X270850Y595051D01*
Y572020D01*
X267800Y568970D01*
Y556619D01*
X267816Y556603D01*
Y546872D01*
X265857Y544913D01*
Y535062D01*
X270024Y530895D01*
Y487198D01*
X272550Y484672D01*
Y477931D01*
X266250Y471631D01*
Y458414D01*
X278938Y445726D01*
X290527D01*
X307903Y428350D01*
X321948D01*
X330999Y419299D01*
Y407756D01*
X321643Y398400D01*
X314136D01*
X309400Y393664D01*
Y368800D01*
X311400Y366800D01*
X316700D01*
X319297Y364203D01*
Y274697D01*
X315500Y270900D01*
Y194500D01*
X318798Y191202D01*
Y166302D01*
X324873Y160227D01*
Y145329D01*
X305356Y125812D01*
Y38069D01*
X308220Y35205D01*
Y31671D01*
X322691Y17200D01*
X326610D01*
X332440Y11370D01*
X553752D01*
X560251Y17869D01*
Y30681D01*
X566133Y36563D01*
Y60482D01*
X567089Y61438D01*
Y66290D01*
X565456Y67923D01*
Y81085D01*
X581500Y97129D01*
Y176749D01*
X590507Y185756D01*
Y338443D01*
X592955Y340891D01*
Y374980D01*
X597850Y379875D01*
Y406467D01*
X590430Y413887D01*
Y534930D01*
X606600Y551100D01*
G01X308687Y519193D02*
Y529876D01*
X307903Y530660D01*
Y539583D01*
X310003Y541683D01*
Y555180D01*
X310600Y555777D01*
Y577843D01*
X311600Y578843D01*
Y585892D01*
X319991Y594283D01*
Y625285D01*
X323100Y628394D01*
Y641136D01*
X325375Y643411D01*
X325993D01*
X329853Y647271D01*
Y648270D01*
X331350Y649767D01*
Y652310D01*
X329618Y654042D01*
X327658D01*
X313800Y667900D01*
Y682950D01*
X321550Y690700D01*
X328100D01*
X331500Y694100D01*
Y705000D01*
X334800Y708300D01*
Y712900D01*
X340100Y718200D01*
G01X461736Y111300D02*
X461136Y110700D01*
X461043D01*
X455497Y105154D01*
X413828D01*
X399890Y119092D01*
Y146650D01*
X400430Y147190D01*
G01X640968Y370425D02*
Y359869D01*
X634101Y353002D01*
Y324403D01*
X612000Y302302D01*
Y219706D01*
X620160Y211546D01*
Y203500D01*
G01X640968Y370425D02*
Y374200D01*
X640520Y374648D01*
Y379149D01*
X644370Y382999D01*
Y384164D01*
X655006Y394800D01*
X663459D01*
X688450Y419791D01*
Y454720D01*
X688500Y454770D01*
Y458400D01*
X690300Y460200D01*
G01X616160Y542700D02*
X615660Y543200D01*
Y559590D01*
X614000Y561250D01*
G01X725000Y576100D02*
Y577351D01*
X705287Y597064D01*
X702515D01*
G01X710100Y545600D02*
X712900Y548400D01*
X720636D01*
X730600Y558364D01*
Y589125D01*
X713525Y606200D01*
X706000D01*
X703800Y608400D01*
G01X717450Y551554D02*
X720254D01*
X728100Y559400D01*
Y588089D01*
X713151Y603038D01*
X712708D01*
G01X831504Y199129D02*
X832327Y199952D01*
X834238D01*
X871190Y236904D01*
Y318743D01*
X873450Y321003D01*
X873503D01*
X878500Y326000D01*
Y388334D01*
X897100Y406934D01*
Y458818D01*
X846120Y509798D01*
X782802D01*
X781700Y510900D01*
G01X821962Y189277D02*
X822760Y190075D01*
Y203059D01*
X862057Y242356D01*
Y305160D01*
X849854Y317363D01*
Y353995D01*
X829830Y374019D01*
G01X850950Y489300D02*
X853398Y486852D01*
Y414933D01*
X852866Y414401D01*
Y414361D01*
X852600Y414095D01*
Y408970D01*
X853200Y408370D01*
Y406630D01*
X852600Y406030D01*
Y355492D01*
X852854Y355238D01*
Y318606D01*
X865057Y306403D01*
Y237353D01*
X832148Y204444D01*
G01X829830Y374019D02*
X814895D01*
X814592Y374322D01*
G54D18*
G01X100250Y530950D02*
X103422Y527778D01*
Y519922D01*
X99300Y515800D01*
X53250D01*
X48200Y520850D01*
Y562215D01*
X53302Y567317D01*
G01X59200Y582200D02*
Y573215D01*
X53302Y567317D01*
G01X762000Y113000D02*
X757800Y117200D01*
Y140750D01*
X754000Y144550D01*
Y172700D01*
G54D19*
G01X710469Y292300D02*
X711283Y293114D01*
X718990D01*
X721359Y290745D01*
Y289680D01*
X723539Y287500D01*
X724596D01*
X727800Y284296D01*
Y281146D01*
X729709Y279237D01*
Y276307D01*
X733859Y272157D01*
Y272048D01*
M02*
